FILE_TYPE = MACRO_DRAWING;
SET COLOR_WIRE YELLOW;
SET COLOR_PROP ORANGE;
SET COLOR_DOT WHITE;
SET COLOR_ARC YELLOW;
SET COLOR_BODY GREEN;
SET COLOR_NOTE PURPLE;
SET PROP_DISPLAY VALUE;
SET PAGE_NUMBER P42;
FORCEADD GENOA_SP5..6
(-4600 3775);
FORCEPROP 1 LAST LOCATION U26
J 0
(-5245 6606);
DISPLAY 0.489362 (-5245 6606);
PAINT SKYBLUE (-5245 6606);
FORCEPROP 0 LAST $SEC 6
J 0
(-5225 6650);
DISPLAY 0.680851 (-5225 6650);
PAINT MONO (-5225 6650);
DISPLAY INVISIBLE (-5225 6650);
FORCEPROP 0 LAST CDS_SEC 6
J 0
(-5250 6575);
DISPLAY 1.021277 (-5250 6575);
DISPLAY INVISIBLE (-5250 6575);
FORCEPROP 0 LASTPIN (-5400 3150) $PN BC67
J 2
(-5410 3160);
DISPLAY 0.489362 (-5410 3160);
PAINT MONO (-5410 3160);
FORCEPROP 0 LASTPIN (-5400 3100) $PN BD67
J 2
(-5410 3110);
DISPLAY 0.489362 (-5410 3110);
PAINT MONO (-5410 3110);
FORCEPROP 0 LASTPIN (-5400 2000) $PN BF67
J 2
(-5410 2010);
DISPLAY 0.489362 (-5410 2010);
PAINT MONO (-5410 2010);
FORCEPROP 0 LASTPIN (-5400 1950) $PN BG67
J 2
(-5410 1960);
DISPLAY 0.489362 (-5410 1960);
PAINT MONO (-5410 1960);
FORCEPROP 0 LASTPIN (-5400 2300) $PN AT65
J 2
(-5410 2310);
DISPLAY 0.489362 (-5410 2310);
PAINT MONO (-5410 2310);
FORCEPROP 0 LASTPIN (-5400 2200) $PN AU66
J 2
(-5410 2210);
DISPLAY 0.489362 (-5410 2210);
PAINT MONO (-5410 2210);
FORCEPROP 0 LASTPIN (-5400 3000) $PN AV67
J 2
(-5410 3010);
DISPLAY 0.489362 (-5410 3010);
PAINT MONO (-5410 3010);
FORCEPROP 0 LASTPIN (-5400 2950) $PN AW66
J 2
(-5410 2960);
DISPLAY 0.489362 (-5410 2960);
PAINT MONO (-5410 2960);
FORCEPROP 0 LASTPIN (-5400 2850) $PN BN66
J 2
(-5410 2860);
DISPLAY 0.489362 (-5410 2860);
PAINT MONO (-5410 2860);
FORCEPROP 0 LASTPIN (-5400 1850) $PN AU67
J 2
(-5410 1860);
DISPLAY 0.489362 (-5410 1860);
PAINT MONO (-5410 1860);
FORCEPROP 0 LASTPIN (-5400 1800) $PN AV65
J 2
(-5410 1810);
DISPLAY 0.489362 (-5410 1810);
PAINT MONO (-5410 1810);
FORCEPROP 0 LASTPIN (-5400 1700) $PN BP65
J 2
(-5410 1710);
DISPLAY 0.489362 (-5410 1710);
PAINT MONO (-5410 1710);
FORCEPROP 0 LASTPIN (-5400 4000) $PN AW67
J 2
(-5410 4010);
DISPLAY 0.489362 (-5410 4010);
PAINT MONO (-5410 4010);
FORCEPROP 0 LASTPIN (-5400 3950) $PN AY67
J 2
(-5410 3960);
DISPLAY 0.489362 (-5410 3960);
PAINT MONO (-5410 3960);
FORCEPROP 0 LASTPIN (-5400 3900) $PN AY65
J 2
(-5410 3910);
DISPLAY 0.489362 (-5410 3910);
PAINT MONO (-5410 3910);
FORCEPROP 0 LASTPIN (-5400 3850) $PN BA66
J 2
(-5410 3860);
DISPLAY 0.489362 (-5410 3860);
PAINT MONO (-5410 3860);
FORCEPROP 0 LASTPIN (-5400 3800) $PN BA67
J 2
(-5410 3810);
DISPLAY 0.489362 (-5410 3810);
PAINT MONO (-5410 3810);
FORCEPROP 0 LASTPIN (-5400 3750) $PN BB67
J 2
(-5410 3760);
DISPLAY 0.489362 (-5410 3760);
PAINT MONO (-5410 3760);
FORCEPROP 0 LASTPIN (-5400 3700) $PN BB65
J 2
(-5410 3710);
DISPLAY 0.489362 (-5410 3710);
PAINT MONO (-5410 3710);
FORCEPROP 0 LASTPIN (-3800 2550) $PN AJ67
J 0
(-3790 2560);
DISPLAY 0.489362 (-3790 2560);
PAINT MONO (-3790 2560);
FORCEPROP 0 LASTPIN (-3800 2500) $PN AK65
J 0
(-3790 2510);
DISPLAY 0.489362 (-3790 2510);
PAINT MONO (-3790 2510);
FORCEPROP 0 LASTPIN (-3800 2450) $PN AK67
J 0
(-3790 2460);
DISPLAY 0.489362 (-3790 2460);
PAINT MONO (-3790 2460);
FORCEPROP 0 LASTPIN (-3800 2400) $PN AL66
J 0
(-3790 2410);
DISPLAY 0.489362 (-3790 2410);
PAINT MONO (-3790 2410);
FORCEPROP 0 LASTPIN (-3800 2350) $PN AN67
J 0
(-3790 2360);
DISPLAY 0.489362 (-3790 2360);
PAINT MONO (-3790 2360);
FORCEPROP 0 LASTPIN (-3800 2300) $PN AP65
J 0
(-3790 2310);
DISPLAY 0.489362 (-3790 2310);
PAINT MONO (-3790 2310);
FORCEPROP 0 LASTPIN (-3800 2250) $PN AP67
J 0
(-3790 2260);
DISPLAY 0.489362 (-3790 2260);
PAINT MONO (-3790 2260);
FORCEPROP 0 LASTPIN (-3800 2200) $PN AR66
J 0
(-3790 2210);
DISPLAY 0.489362 (-3790 2210);
PAINT MONO (-3790 2210);
FORCEPROP 0 LASTPIN (-3800 6150) $PN E67
J 0
(-3790 6160);
DISPLAY 0.489362 (-3790 6160);
PAINT MONO (-3790 6160);
FORCEPROP 0 LASTPIN (-3800 6100) $PN F65
J 0
(-3790 6110);
DISPLAY 0.489362 (-3790 6110);
PAINT MONO (-3790 6110);
FORCEPROP 0 LASTPIN (-3800 6050) $PN F67
J 0
(-3790 6060);
DISPLAY 0.489362 (-3790 6060);
PAINT MONO (-3790 6060);
FORCEPROP 0 LASTPIN (-3800 6000) $PN G66
J 0
(-3790 6010);
DISPLAY 0.489362 (-3790 6010);
PAINT MONO (-3790 6010);
FORCEPROP 0 LASTPIN (-3800 5950) $PN J67
J 0
(-3790 5960);
DISPLAY 0.489362 (-3790 5960);
PAINT MONO (-3790 5960);
FORCEPROP 0 LASTPIN (-3800 5900) $PN K65
J 0
(-3790 5910);
DISPLAY 0.489362 (-3790 5910);
PAINT MONO (-3790 5910);
FORCEPROP 0 LASTPIN (-3800 5850) $PN K67
J 0
(-3790 5860);
DISPLAY 0.489362 (-3790 5860);
PAINT MONO (-3790 5860);
FORCEPROP 0 LASTPIN (-3800 5800) $PN L66
J 0
(-3790 5810);
DISPLAY 0.489362 (-3790 5810);
PAINT MONO (-3790 5810);
FORCEPROP 0 LASTPIN (-3800 5700) $PN L67
J 0
(-3790 5710);
DISPLAY 0.489362 (-3790 5710);
PAINT MONO (-3790 5710);
FORCEPROP 0 LASTPIN (-3800 5650) $PN M65
J 0
(-3790 5660);
DISPLAY 0.489362 (-3790 5660);
PAINT MONO (-3790 5660);
FORCEPROP 0 LASTPIN (-3800 5600) $PN M67
J 0
(-3790 5610);
DISPLAY 0.489362 (-3790 5610);
PAINT MONO (-3790 5610);
FORCEPROP 0 LASTPIN (-3800 5550) $PN N66
J 0
(-3790 5560);
DISPLAY 0.489362 (-3790 5560);
PAINT MONO (-3790 5560);
FORCEPROP 0 LASTPIN (-3800 5500) $PN R67
J 0
(-3790 5510);
DISPLAY 0.489362 (-3790 5510);
PAINT MONO (-3790 5510);
FORCEPROP 0 LASTPIN (-3800 5450) $PN T65
J 0
(-3790 5460);
DISPLAY 0.489362 (-3790 5460);
PAINT MONO (-3790 5460);
FORCEPROP 0 LASTPIN (-3800 5400) $PN T67
J 0
(-3790 5410);
DISPLAY 0.489362 (-3790 5410);
PAINT MONO (-3790 5410);
FORCEPROP 0 LASTPIN (-3800 5350) $PN U66
J 0
(-3790 5360);
DISPLAY 0.489362 (-3790 5360);
PAINT MONO (-3790 5360);
FORCEPROP 0 LASTPIN (-3800 5250) $PN U67
J 0
(-3790 5260);
DISPLAY 0.489362 (-3790 5260);
PAINT MONO (-3790 5260);
FORCEPROP 0 LASTPIN (-3800 5200) $PN V65
J 0
(-3790 5210);
DISPLAY 0.489362 (-3790 5210);
PAINT MONO (-3790 5210);
FORCEPROP 0 LASTPIN (-3800 5150) $PN V67
J 0
(-3790 5160);
DISPLAY 0.489362 (-3790 5160);
PAINT MONO (-3790 5160);
FORCEPROP 0 LASTPIN (-3800 5100) $PN W66
J 0
(-3790 5110);
DISPLAY 0.489362 (-3790 5110);
PAINT MONO (-3790 5110);
FORCEPROP 0 LASTPIN (-3800 5050) $PN AA67
J 0
(-3790 5060);
DISPLAY 0.489362 (-3790 5060);
PAINT MONO (-3790 5060);
FORCEPROP 0 LASTPIN (-3800 5000) $PN AB65
J 0
(-3790 5010);
DISPLAY 0.489362 (-3790 5010);
PAINT MONO (-3790 5010);
FORCEPROP 0 LASTPIN (-3800 4950) $PN AB67
J 0
(-3790 4960);
DISPLAY 0.489362 (-3790 4960);
PAINT MONO (-3790 4960);
FORCEPROP 0 LASTPIN (-3800 4900) $PN AC66
J 0
(-3790 4910);
DISPLAY 0.489362 (-3790 4910);
PAINT MONO (-3790 4910);
FORCEPROP 0 LASTPIN (-3800 4800) $PN AC67
J 0
(-3790 4810);
DISPLAY 0.489362 (-3790 4810);
PAINT MONO (-3790 4810);
FORCEPROP 0 LASTPIN (-3800 4750) $PN AD65
J 0
(-3790 4760);
DISPLAY 0.489362 (-3790 4760);
PAINT MONO (-3790 4760);
FORCEPROP 0 LASTPIN (-3800 4700) $PN AD67
J 0
(-3790 4710);
DISPLAY 0.489362 (-3790 4710);
PAINT MONO (-3790 4710);
FORCEPROP 0 LASTPIN (-3800 4650) $PN AE66
J 0
(-3790 4660);
DISPLAY 0.489362 (-3790 4660);
PAINT MONO (-3790 4660);
FORCEPROP 0 LASTPIN (-3800 4600) $PN AG67
J 0
(-3790 4610);
DISPLAY 0.489362 (-3790 4610);
PAINT MONO (-3790 4610);
FORCEPROP 0 LASTPIN (-3800 4550) $PN AH65
J 0
(-3790 4560);
DISPLAY 0.489362 (-3790 4560);
PAINT MONO (-3790 4560);
FORCEPROP 0 LASTPIN (-3800 4500) $PN AH67
J 0
(-3790 4510);
DISPLAY 0.489362 (-3790 4510);
PAINT MONO (-3790 4510);
FORCEPROP 0 LASTPIN (-3800 4450) $PN AJ66
J 0
(-3790 4460);
DISPLAY 0.489362 (-3790 4460);
PAINT MONO (-3790 4460);
FORCEPROP 0 LASTPIN (-5400 6150) $PN G67
J 2
(-5410 6160);
DISPLAY 0.489362 (-5410 6160);
PAINT MONO (-5410 6160);
FORCEPROP 0 LASTPIN (-5400 6050) $PN N67
J 2
(-5410 6060);
DISPLAY 0.489362 (-5410 6060);
PAINT MONO (-5410 6060);
FORCEPROP 0 LASTPIN (-5400 5950) $PN W67
J 2
(-5410 5960);
DISPLAY 0.489362 (-5410 5960);
PAINT MONO (-5410 5960);
FORCEPROP 0 LASTPIN (-5400 5850) $PN AE67
J 2
(-5410 5860);
DISPLAY 0.489362 (-5410 5860);
PAINT MONO (-5410 5860);
FORCEPROP 0 LASTPIN (-5400 5750) $PN AL67
J 2
(-5410 5760);
DISPLAY 0.489362 (-5410 5760);
PAINT MONO (-5410 5760);
FORCEPROP 0 LASTPIN (-5400 5650) $PN J66
J 2
(-5410 5660);
DISPLAY 0.489362 (-5410 5660);
PAINT MONO (-5410 5660);
FORCEPROP 0 LASTPIN (-5400 5550) $PN R66
J 2
(-5410 5560);
DISPLAY 0.489362 (-5410 5560);
PAINT MONO (-5410 5560);
FORCEPROP 0 LASTPIN (-5400 5450) $PN AA66
J 2
(-5410 5460);
DISPLAY 0.489362 (-5410 5460);
PAINT MONO (-5410 5460);
FORCEPROP 0 LASTPIN (-5400 5350) $PN AG66
J 2
(-5410 5360);
DISPLAY 0.489362 (-5410 5360);
PAINT MONO (-5410 5360);
FORCEPROP 0 LASTPIN (-5400 5250) $PN AN66
J 2
(-5410 5260);
DISPLAY 0.489362 (-5410 5260);
PAINT MONO (-5410 5260);
FORCEPROP 0 LASTPIN (-5400 6100) $PN H67
J 2
(-5410 6110);
DISPLAY 0.489362 (-5410 6110);
PAINT MONO (-5410 6110);
FORCEPROP 0 LASTPIN (-5400 6000) $PN P67
J 2
(-5410 6010);
DISPLAY 0.489362 (-5410 6010);
PAINT MONO (-5410 6010);
FORCEPROP 0 LASTPIN (-5400 5900) $PN Y67
J 2
(-5410 5910);
DISPLAY 0.489362 (-5410 5910);
PAINT MONO (-5410 5910);
FORCEPROP 0 LASTPIN (-5400 5800) $PN AF67
J 2
(-5410 5810);
DISPLAY 0.489362 (-5410 5810);
PAINT MONO (-5410 5810);
FORCEPROP 0 LASTPIN (-5400 5700) $PN AM67
J 2
(-5410 5710);
DISPLAY 0.489362 (-5410 5710);
PAINT MONO (-5410 5710);
FORCEPROP 0 LASTPIN (-5400 5600) $PN H65
J 2
(-5410 5610);
DISPLAY 0.489362 (-5410 5610);
PAINT MONO (-5410 5610);
FORCEPROP 0 LASTPIN (-5400 5500) $PN P65
J 2
(-5410 5510);
DISPLAY 0.489362 (-5410 5510);
PAINT MONO (-5410 5510);
FORCEPROP 0 LASTPIN (-5400 5400) $PN Y65
J 2
(-5410 5410);
DISPLAY 0.489362 (-5410 5410);
PAINT MONO (-5410 5410);
FORCEPROP 0 LASTPIN (-5400 5300) $PN AF65
J 2
(-5410 5310);
DISPLAY 0.489362 (-5410 5310);
PAINT MONO (-5410 5310);
FORCEPROP 0 LASTPIN (-5400 5200) $PN AM65
J 2
(-5410 5210);
DISPLAY 0.489362 (-5410 5210);
PAINT MONO (-5410 5210);
FORCEPROP 0 LASTPIN (-5400 2750) $PN BC66
J 2
(-5410 2760);
DISPLAY 0.489362 (-5410 2760);
PAINT MONO (-5410 2760);
FORCEPROP 0 LASTPIN (-5400 2650) $PN BM65
J 2
(-5410 2660);
DISPLAY 0.489362 (-5410 2660);
PAINT MONO (-5410 2660);
FORCEPROP 0 LASTPIN (-5400 2600) $PN BN67
J 2
(-5410 2610);
DISPLAY 0.489362 (-5410 2610);
PAINT MONO (-5410 2610);
FORCEPROP 0 LASTPIN (-5400 2500) $PN BP67
J 2
(-5410 2510);
DISPLAY 0.489362 (-5410 2510);
PAINT MONO (-5410 2510);
FORCEPROP 0 LASTPIN (-5400 1600) $PN BL66
J 2
(-5410 1610);
DISPLAY 0.489362 (-5410 1610);
PAINT MONO (-5410 1610);
FORCEPROP 0 LASTPIN (-5400 1550) $PN BM67
J 2
(-5410 1560);
DISPLAY 0.489362 (-5410 1560);
PAINT MONO (-5410 1560);
FORCEPROP 0 LASTPIN (-5400 1450) $PN BR67
J 2
(-5410 1460);
DISPLAY 0.489362 (-5410 1460);
PAINT MONO (-5410 1460);
FORCEPROP 0 LASTPIN (-5400 3600) $PN BG66
J 2
(-5410 3610);
DISPLAY 0.489362 (-5410 3610);
PAINT MONO (-5410 3610);
FORCEPROP 0 LASTPIN (-5400 3550) $PN BH65
J 2
(-5410 3560);
DISPLAY 0.489362 (-5410 3560);
PAINT MONO (-5410 3560);
FORCEPROP 0 LASTPIN (-5400 3500) $PN BH67
J 2
(-5410 3510);
DISPLAY 0.489362 (-5410 3510);
PAINT MONO (-5410 3510);
FORCEPROP 0 LASTPIN (-5400 3450) $PN BJ67
J 2
(-5410 3460);
DISPLAY 0.489362 (-5410 3460);
PAINT MONO (-5410 3460);
FORCEPROP 0 LASTPIN (-5400 3400) $PN BJ66
J 2
(-5410 3410);
DISPLAY 0.489362 (-5410 3410);
PAINT MONO (-5410 3410);
FORCEPROP 0 LASTPIN (-5400 3350) $PN BK65
J 2
(-5410 3360);
DISPLAY 0.489362 (-5410 3360);
PAINT MONO (-5410 3360);
FORCEPROP 0 LASTPIN (-5400 3300) $PN BK67
J 2
(-5410 3310);
DISPLAY 0.489362 (-5410 3310);
PAINT MONO (-5410 3310);
FORCEPROP 0 LASTPIN (-3800 2100) $PN BY67
J 0
(-3790 2110);
DISPLAY 0.489362 (-3790 2110);
PAINT MONO (-3790 2110);
FORCEPROP 0 LASTPIN (-3800 2050) $PN CA66
J 0
(-3790 2060);
DISPLAY 0.489362 (-3790 2060);
PAINT MONO (-3790 2060);
FORCEPROP 0 LASTPIN (-3800 2000) $PN CA67
J 0
(-3790 2010);
DISPLAY 0.489362 (-3790 2010);
PAINT MONO (-3790 2010);
FORCEPROP 0 LASTPIN (-3800 1950) $PN CB65
J 0
(-3790 1960);
DISPLAY 0.489362 (-3790 1960);
PAINT MONO (-3790 1960);
FORCEPROP 0 LASTPIN (-3800 1900) $PN BT67
J 0
(-3790 1910);
DISPLAY 0.489362 (-3790 1910);
PAINT MONO (-3790 1910);
FORCEPROP 0 LASTPIN (-3800 1850) $PN BU66
J 0
(-3790 1860);
DISPLAY 0.489362 (-3790 1860);
PAINT MONO (-3790 1860);
FORCEPROP 0 LASTPIN (-3800 1800) $PN BU67
J 0
(-3790 1810);
DISPLAY 0.489362 (-3790 1810);
PAINT MONO (-3790 1810);
FORCEPROP 0 LASTPIN (-3800 1750) $PN BV65
J 0
(-3790 1760);
DISPLAY 0.489362 (-3790 1760);
PAINT MONO (-3790 1760);
FORCEPROP 0 LASTPIN (-3800 4350) $PN CB67
J 0
(-3790 4360);
DISPLAY 0.489362 (-3790 4360);
PAINT MONO (-3790 4360);
FORCEPROP 0 LASTPIN (-3800 4300) $PN CC66
J 0
(-3790 4310);
DISPLAY 0.489362 (-3790 4310);
PAINT MONO (-3790 4310);
FORCEPROP 0 LASTPIN (-3800 4250) $PN CC67
J 0
(-3790 4260);
DISPLAY 0.489362 (-3790 4260);
PAINT MONO (-3790 4260);
FORCEPROP 0 LASTPIN (-3800 4200) $PN CD65
J 0
(-3790 4210);
DISPLAY 0.489362 (-3790 4210);
PAINT MONO (-3790 4210);
FORCEPROP 0 LASTPIN (-3800 4150) $PN CF67
J 0
(-3790 4160);
DISPLAY 0.489362 (-3790 4160);
PAINT MONO (-3790 4160);
FORCEPROP 0 LASTPIN (-3800 4100) $PN CG66
J 0
(-3790 4110);
DISPLAY 0.489362 (-3790 4110);
PAINT MONO (-3790 4110);
FORCEPROP 0 LASTPIN (-3800 4050) $PN CG67
J 0
(-3790 4060);
DISPLAY 0.489362 (-3790 4060);
PAINT MONO (-3790 4060);
FORCEPROP 0 LASTPIN (-3800 4000) $PN CH65
J 0
(-3790 4010);
DISPLAY 0.489362 (-3790 4010);
PAINT MONO (-3790 4010);
FORCEPROP 0 LASTPIN (-3800 3900) $PN CH67
J 0
(-3790 3910);
DISPLAY 0.489362 (-3790 3910);
PAINT MONO (-3790 3910);
FORCEPROP 0 LASTPIN (-3800 3850) $PN CJ66
J 0
(-3790 3860);
DISPLAY 0.489362 (-3790 3860);
PAINT MONO (-3790 3860);
FORCEPROP 0 LASTPIN (-3800 3800) $PN CJ67
J 0
(-3790 3810);
DISPLAY 0.489362 (-3790 3810);
PAINT MONO (-3790 3810);
FORCEPROP 0 LASTPIN (-3800 3750) $PN CK65
J 0
(-3790 3760);
DISPLAY 0.489362 (-3790 3760);
PAINT MONO (-3790 3760);
FORCEPROP 0 LASTPIN (-3800 3700) $PN CM67
J 0
(-3790 3710);
DISPLAY 0.489362 (-3790 3710);
PAINT MONO (-3790 3710);
FORCEPROP 0 LASTPIN (-3800 3650) $PN CN66
J 0
(-3790 3660);
DISPLAY 0.489362 (-3790 3660);
PAINT MONO (-3790 3660);
FORCEPROP 0 LASTPIN (-3800 3600) $PN CN67
J 0
(-3790 3610);
DISPLAY 0.489362 (-3790 3610);
PAINT MONO (-3790 3610);
FORCEPROP 0 LASTPIN (-3800 3550) $PN CP65
J 0
(-3790 3560);
DISPLAY 0.489362 (-3790 3560);
PAINT MONO (-3790 3560);
FORCEPROP 0 LASTPIN (-3800 3450) $PN CP67
J 0
(-3790 3460);
DISPLAY 0.489362 (-3790 3460);
PAINT MONO (-3790 3460);
FORCEPROP 0 LASTPIN (-3800 3400) $PN CR66
J 0
(-3790 3410);
DISPLAY 0.489362 (-3790 3410);
PAINT MONO (-3790 3410);
FORCEPROP 0 LASTPIN (-3800 3350) $PN CR67
J 0
(-3790 3360);
DISPLAY 0.489362 (-3790 3360);
PAINT MONO (-3790 3360);
FORCEPROP 0 LASTPIN (-3800 3300) $PN CT65
J 0
(-3790 3310);
DISPLAY 0.489362 (-3790 3310);
PAINT MONO (-3790 3310);
FORCEPROP 0 LASTPIN (-3800 3250) $PN CV67
J 0
(-3790 3260);
DISPLAY 0.489362 (-3790 3260);
PAINT MONO (-3790 3260);
FORCEPROP 0 LASTPIN (-3800 3200) $PN CW66
J 0
(-3790 3210);
DISPLAY 0.489362 (-3790 3210);
PAINT MONO (-3790 3210);
FORCEPROP 0 LASTPIN (-3800 3150) $PN CW67
J 0
(-3790 3160);
DISPLAY 0.489362 (-3790 3160);
PAINT MONO (-3790 3160);
FORCEPROP 0 LASTPIN (-3800 3100) $PN CY65
J 0
(-3790 3110);
DISPLAY 0.489362 (-3790 3110);
PAINT MONO (-3790 3110);
FORCEPROP 0 LASTPIN (-3800 3000) $PN CY67
J 0
(-3790 3010);
DISPLAY 0.489362 (-3790 3010);
PAINT MONO (-3790 3010);
FORCEPROP 0 LASTPIN (-3800 2950) $PN DA66
J 0
(-3790 2960);
DISPLAY 0.489362 (-3790 2960);
PAINT MONO (-3790 2960);
FORCEPROP 0 LASTPIN (-3800 2900) $PN DA67
J 0
(-3790 2910);
DISPLAY 0.489362 (-3790 2910);
PAINT MONO (-3790 2910);
FORCEPROP 0 LASTPIN (-3800 2850) $PN DB65
J 0
(-3790 2860);
DISPLAY 0.489362 (-3790 2860);
PAINT MONO (-3790 2860);
FORCEPROP 0 LASTPIN (-3800 2800) $PN DD67
J 0
(-3790 2810);
DISPLAY 0.489362 (-3790 2810);
PAINT MONO (-3790 2810);
FORCEPROP 0 LASTPIN (-3800 2750) $PN DE66
J 0
(-3790 2760);
DISPLAY 0.489362 (-3790 2760);
PAINT MONO (-3790 2760);
FORCEPROP 0 LASTPIN (-3800 2700) $PN DE67
J 0
(-3790 2710);
DISPLAY 0.489362 (-3790 2710);
PAINT MONO (-3790 2710);
FORCEPROP 0 LASTPIN (-3800 2650) $PN DF67
J 0
(-3790 2660);
DISPLAY 0.489362 (-3790 2660);
PAINT MONO (-3790 2660);
FORCEPROP 0 LASTPIN (-5400 5100) $PN CD67
J 2
(-5410 5110);
DISPLAY 0.489362 (-5410 5110);
PAINT MONO (-5410 5110);
FORCEPROP 0 LASTPIN (-5400 5000) $PN CK67
J 2
(-5410 5010);
DISPLAY 0.489362 (-5410 5010);
PAINT MONO (-5410 5010);
FORCEPROP 0 LASTPIN (-5400 4900) $PN CT67
J 2
(-5410 4910);
DISPLAY 0.489362 (-5410 4910);
PAINT MONO (-5410 4910);
FORCEPROP 0 LASTPIN (-5400 4800) $PN DB67
J 2
(-5410 4810);
DISPLAY 0.489362 (-5410 4810);
PAINT MONO (-5410 4810);
FORCEPROP 0 LASTPIN (-5400 4700) $PN BY65
J 2
(-5410 4710);
DISPLAY 0.489362 (-5410 4710);
PAINT MONO (-5410 4710);
FORCEPROP 0 LASTPIN (-5400 4600) $PN CF65
J 2
(-5410 4610);
DISPLAY 0.489362 (-5410 4610);
PAINT MONO (-5410 4610);
FORCEPROP 0 LASTPIN (-5400 4500) $PN CM65
J 2
(-5410 4510);
DISPLAY 0.489362 (-5410 4510);
PAINT MONO (-5410 4510);
FORCEPROP 0 LASTPIN (-5400 4400) $PN CV65
J 2
(-5410 4410);
DISPLAY 0.489362 (-5410 4410);
PAINT MONO (-5410 4410);
FORCEPROP 0 LASTPIN (-5400 4300) $PN DD65
J 2
(-5410 4310);
DISPLAY 0.489362 (-5410 4310);
PAINT MONO (-5410 4310);
FORCEPROP 0 LASTPIN (-5400 4200) $PN BV67
J 2
(-5410 4210);
DISPLAY 0.489362 (-5410 4210);
PAINT MONO (-5410 4210);
FORCEPROP 0 LASTPIN (-5400 5050) $PN CE67
J 2
(-5410 5060);
DISPLAY 0.489362 (-5410 5060);
PAINT MONO (-5410 5060);
FORCEPROP 0 LASTPIN (-5400 4950) $PN CL67
J 2
(-5410 4960);
DISPLAY 0.489362 (-5410 4960);
PAINT MONO (-5410 4960);
FORCEPROP 0 LASTPIN (-5400 4850) $PN CU67
J 2
(-5410 4860);
DISPLAY 0.489362 (-5410 4860);
PAINT MONO (-5410 4860);
FORCEPROP 0 LASTPIN (-5400 4750) $PN DC67
J 2
(-5410 4760);
DISPLAY 0.489362 (-5410 4760);
PAINT MONO (-5410 4760);
FORCEPROP 0 LASTPIN (-5400 4650) $PN BW66
J 2
(-5410 4660);
DISPLAY 0.489362 (-5410 4660);
PAINT MONO (-5410 4660);
FORCEPROP 0 LASTPIN (-5400 4550) $PN CE66
J 2
(-5410 4560);
DISPLAY 0.489362 (-5410 4560);
PAINT MONO (-5410 4560);
FORCEPROP 0 LASTPIN (-5400 4450) $PN CL66
J 2
(-5410 4460);
DISPLAY 0.489362 (-5410 4460);
PAINT MONO (-5410 4460);
FORCEPROP 0 LASTPIN (-5400 4350) $PN CU66
J 2
(-5410 4360);
DISPLAY 0.489362 (-5410 4360);
PAINT MONO (-5410 4360);
FORCEPROP 0 LASTPIN (-5400 4250) $PN DC66
J 2
(-5410 4260);
DISPLAY 0.489362 (-5410 4260);
PAINT MONO (-5410 4260);
FORCEPROP 0 LASTPIN (-5400 4150) $PN BW67
J 2
(-5410 4160);
DISPLAY 0.489362 (-5410 4160);
PAINT MONO (-5410 4160);
FORCEPROP 0 LASTPIN (-5400 2400) $PN BL67
J 2
(-5410 2410);
DISPLAY 0.489362 (-5410 2410);
PAINT MONO (-5410 2410);
FORCEPROP 0 LASTPIN (-5400 1350) $PN BF65
J 2
(-5410 1360);
DISPLAY 0.489362 (-5410 1360);
PAINT MONO (-5410 1360);
FORCEPROP 2 LAST PART_TYPE SMLF
J 0
(-5250 6525);
DISPLAY 1.021277 (-5250 6525);
FORCEPROP 1 LAST MATERIAL IO
J 0
(-5245 6332);
DISPLAY 0.489362 (-5245 6332);
PAINT SKYBLUE (-5245 6332);
FORCEPROP 2 LAST VALUE SOCKET6096_13568-001
J 0
(-5250 6425);
DISPLAY 0.489362 (-5250 6425);
PAINT SKYBLUE (-5250 6425);
FORCEPROP 1 LAST PART_NUMBER DGA^6000030
J 0
(-5245 6459);
DISPLAY 0.489362 (-5245 6459);
PAINT SKYBLUE (-5245 6459);
FORCEPROP 2 LAST CDS_LIB pure_quanta
J 0
(-4600 3775);
DISPLAY INVISIBLE (-4600 3775);
FORCEPROP 1 LAST CDS_LMAN_SYM_OUTLINE -650,2525,650,-2525
J 0
(-4600 3775);
DISPLAY 0.468085 (-4600 3775);
PAINT GREEN (-4600 3775);
DISPLAY INVISIBLE (-4600 3775);
FORCEPROP 1 LAST NEEDS_NO_SIZE TRUE
J 0
(-4600 3775);
DISPLAY 0.723404 (-4600 3775);
PAINT GREEN (-4600 3775);
DISPLAY INVISIBLE (-4600 3775);
FORCEPROP 1 LAST PATH I159
J 0
(-4600 3775);
DISPLAY 0.723404 (-4600 3775);
PAINT GREEN (-4600 3775);
DISPLAY INVISIBLE (-4600 3775);
FORCEADD TAP..1
(-3325 6150);
FORCEPROP 3 LASTPIN (-3375 6150) SIG_NAME M_F_CPU1_SA_DQ<0>
J 0
(-3365 6160);
DISPLAY 0.659574 (-3365 6160);
PAINT MONO (-3365 6160);
DISPLAY INVISIBLE (-3365 6160);
FORCEPROP 1 LASTPIN (-3375 6150) BN 0
J 0
(-3387 6158);
DISPLAY 0.489362 (-3387 6158);
PAINT GREEN (-3387 6158);
FORCEPROP 2 LAST CDS_LIB mstr_standard
J 0
(-3325 6150);
DISPLAY 0.723404 (-3325 6150);
PAINT MONO (-3325 6150);
DISPLAY INVISIBLE (-3325 6150);
FORCEPROP 1 LAST BODY_TYPE PLUMBING
J 0
(-3325 6200);
DISPLAY 0.872340 (-3325 6200);
PAINT GREEN (-3325 6200);
DISPLAY INVISIBLE (-3325 6200);
FORCEPROP 1 LAST HDL_TAP TRUE
J 0
(-3000 6025);
DISPLAY 0.872340 (-3000 6025);
DISPLAY INVISIBLE (-3000 6025);
FORCEPROP 1 LAST PATH I160
J 0
(-3327 6150);
DISPLAY 0.872340 (-3327 6150);
PAINT GREEN (-3327 6150);
DISPLAY INVISIBLE (-3327 6150);
FORCEADD OFFPAGE..3
(-2600 6175);
FORCEPROP 2 LAST $XR0 102 
J 0
(-2386 6175);
DISPLAY 0.638298 (-2386 6175);
PAINT MONO (-2386 6175);
FORCEPROP 2 LAST PATH I161
J 0
(-2375 6225);
DISPLAY 1.021277 (-2375 6225);
DISPLAY INVISIBLE (-2375 6225);
FORCEPROP 1 LAST COMMENT_BODY TRUE
J 0
(-2650 6075);
DISPLAY 0.872340 (-2650 6075);
PAINT GREEN (-2650 6075);
DISPLAY INVISIBLE (-2650 6075);
FORCEPROP 1 LAST OFFPAGE TRUE
J 0
(-2275 6050);
DISPLAY 0.872340 (-2275 6050);
PAINT GREEN (-2275 6050);
DISPLAY INVISIBLE (-2275 6050);
FORCEPROP 2 LAST CDS_LIB mstr_standard
J 0
(-2600 6175);
DISPLAY 0.723404 (-2600 6175);
PAINT MONO (-2600 6175);
DISPLAY INVISIBLE (-2600 6175);
FORCEADD OFFPAGE..3
(-2600 4375);
FORCEPROP 2 LAST $XR0 102 
J 0
(-2386 4375);
DISPLAY 0.638298 (-2386 4375);
PAINT MONO (-2386 4375);
FORCEPROP 2 LAST PATH I162
J 0
(-2375 4425);
DISPLAY 1.021277 (-2375 4425);
DISPLAY INVISIBLE (-2375 4425);
FORCEPROP 1 LAST COMMENT_BODY TRUE
J 0
(-2650 4275);
DISPLAY 0.872340 (-2650 4275);
PAINT GREEN (-2650 4275);
DISPLAY INVISIBLE (-2650 4275);
FORCEPROP 1 LAST OFFPAGE TRUE
J 0
(-2275 4250);
DISPLAY 0.872340 (-2275 4250);
PAINT GREEN (-2275 4250);
DISPLAY INVISIBLE (-2275 4250);
FORCEPROP 2 LAST CDS_LIB mstr_standard
J 0
(-2600 4375);
DISPLAY 0.723404 (-2600 4375);
PAINT MONO (-2600 4375);
DISPLAY INVISIBLE (-2600 4375);
FORCEADD TAP..1
(-3325 6100);
FORCEPROP 3 LASTPIN (-3375 6100) SIG_NAME M_F_CPU1_SA_DQ<1>
J 0
(-3365 6110);
DISPLAY 0.659574 (-3365 6110);
PAINT MONO (-3365 6110);
DISPLAY INVISIBLE (-3365 6110);
FORCEPROP 1 LASTPIN (-3375 6100) BN 1
J 0
(-3387 6108);
DISPLAY 0.489362 (-3387 6108);
PAINT GREEN (-3387 6108);
FORCEPROP 2 LAST CDS_LIB mstr_standard
J 0
(-3325 6100);
DISPLAY 0.723404 (-3325 6100);
PAINT MONO (-3325 6100);
DISPLAY INVISIBLE (-3325 6100);
FORCEPROP 1 LAST BODY_TYPE PLUMBING
J 0
(-3325 6150);
DISPLAY 0.872340 (-3325 6150);
PAINT GREEN (-3325 6150);
DISPLAY INVISIBLE (-3325 6150);
FORCEPROP 1 LAST HDL_TAP TRUE
J 0
(-3000 5975);
DISPLAY 0.872340 (-3000 5975);
DISPLAY INVISIBLE (-3000 5975);
FORCEPROP 1 LAST PATH I163
J 0
(-3327 6100);
DISPLAY 0.872340 (-3327 6100);
PAINT GREEN (-3327 6100);
DISPLAY INVISIBLE (-3327 6100);
FORCEADD TAP..1
(-3325 6050);
FORCEPROP 3 LASTPIN (-3375 6050) SIG_NAME M_F_CPU1_SA_DQ<2>
J 0
(-3365 6060);
DISPLAY 0.659574 (-3365 6060);
PAINT MONO (-3365 6060);
DISPLAY INVISIBLE (-3365 6060);
FORCEPROP 1 LASTPIN (-3375 6050) BN 2
J 0
(-3387 6058);
DISPLAY 0.489362 (-3387 6058);
PAINT GREEN (-3387 6058);
FORCEPROP 2 LAST CDS_LIB mstr_standard
J 0
(-3325 6050);
DISPLAY 0.723404 (-3325 6050);
PAINT MONO (-3325 6050);
DISPLAY INVISIBLE (-3325 6050);
FORCEPROP 1 LAST BODY_TYPE PLUMBING
J 0
(-3325 6100);
DISPLAY 0.872340 (-3325 6100);
PAINT GREEN (-3325 6100);
DISPLAY INVISIBLE (-3325 6100);
FORCEPROP 1 LAST HDL_TAP TRUE
J 0
(-3000 5925);
DISPLAY 0.872340 (-3000 5925);
DISPLAY INVISIBLE (-3000 5925);
FORCEPROP 1 LAST PATH I164
J 0
(-3327 6050);
DISPLAY 0.872340 (-3327 6050);
PAINT GREEN (-3327 6050);
DISPLAY INVISIBLE (-3327 6050);
FORCEADD TAP..1
(-3325 5900);
FORCEPROP 3 LASTPIN (-3375 5900) SIG_NAME M_F_CPU1_SA_DQ<5>
J 0
(-3365 5910);
DISPLAY 0.659574 (-3365 5910);
PAINT MONO (-3365 5910);
DISPLAY INVISIBLE (-3365 5910);
FORCEPROP 1 LASTPIN (-3375 5900) BN 5
J 0
(-3387 5908);
DISPLAY 0.489362 (-3387 5908);
PAINT GREEN (-3387 5908);
FORCEPROP 2 LAST CDS_LIB mstr_standard
J 0
(-3325 5900);
DISPLAY 0.723404 (-3325 5900);
PAINT MONO (-3325 5900);
DISPLAY INVISIBLE (-3325 5900);
FORCEPROP 1 LAST BODY_TYPE PLUMBING
J 0
(-3325 5950);
DISPLAY 0.872340 (-3325 5950);
PAINT GREEN (-3325 5950);
DISPLAY INVISIBLE (-3325 5950);
FORCEPROP 1 LAST HDL_TAP TRUE
J 0
(-3000 5775);
DISPLAY 0.872340 (-3000 5775);
DISPLAY INVISIBLE (-3000 5775);
FORCEPROP 1 LAST PATH I165
J 0
(-3327 5900);
DISPLAY 0.872340 (-3327 5900);
PAINT GREEN (-3327 5900);
DISPLAY INVISIBLE (-3327 5900);
FORCEADD TAP..1
(-3325 6000);
FORCEPROP 3 LASTPIN (-3375 6000) SIG_NAME M_F_CPU1_SA_DQ<3>
J 0
(-3365 6010);
DISPLAY 0.659574 (-3365 6010);
PAINT MONO (-3365 6010);
DISPLAY INVISIBLE (-3365 6010);
FORCEPROP 1 LASTPIN (-3375 6000) BN 3
J 0
(-3387 6008);
DISPLAY 0.489362 (-3387 6008);
PAINT GREEN (-3387 6008);
FORCEPROP 2 LAST CDS_LIB mstr_standard
J 0
(-3325 6000);
DISPLAY 0.723404 (-3325 6000);
PAINT MONO (-3325 6000);
DISPLAY INVISIBLE (-3325 6000);
FORCEPROP 1 LAST BODY_TYPE PLUMBING
J 0
(-3325 6050);
DISPLAY 0.872340 (-3325 6050);
PAINT GREEN (-3325 6050);
DISPLAY INVISIBLE (-3325 6050);
FORCEPROP 1 LAST HDL_TAP TRUE
J 0
(-3000 5875);
DISPLAY 0.872340 (-3000 5875);
DISPLAY INVISIBLE (-3000 5875);
FORCEPROP 1 LAST PATH I166
J 0
(-3327 6000);
DISPLAY 0.872340 (-3327 6000);
PAINT GREEN (-3327 6000);
DISPLAY INVISIBLE (-3327 6000);
FORCEADD TAP..1
(-3325 5950);
FORCEPROP 3 LASTPIN (-3375 5950) SIG_NAME M_F_CPU1_SA_DQ<4>
J 0
(-3365 5960);
DISPLAY 0.659574 (-3365 5960);
PAINT MONO (-3365 5960);
DISPLAY INVISIBLE (-3365 5960);
FORCEPROP 1 LASTPIN (-3375 5950) BN 4
J 0
(-3387 5958);
DISPLAY 0.489362 (-3387 5958);
PAINT GREEN (-3387 5958);
FORCEPROP 2 LAST CDS_LIB mstr_standard
J 0
(-3325 5950);
DISPLAY 0.723404 (-3325 5950);
PAINT MONO (-3325 5950);
DISPLAY INVISIBLE (-3325 5950);
FORCEPROP 1 LAST BODY_TYPE PLUMBING
J 0
(-3325 6000);
DISPLAY 0.872340 (-3325 6000);
PAINT GREEN (-3325 6000);
DISPLAY INVISIBLE (-3325 6000);
FORCEPROP 1 LAST HDL_TAP TRUE
J 0
(-3000 5825);
DISPLAY 0.872340 (-3000 5825);
DISPLAY INVISIBLE (-3000 5825);
FORCEPROP 1 LAST PATH I167
J 0
(-3327 5950);
DISPLAY 0.872340 (-3327 5950);
PAINT GREEN (-3327 5950);
DISPLAY INVISIBLE (-3327 5950);
FORCEADD TAP..1
(-3325 5850);
FORCEPROP 3 LASTPIN (-3375 5850) SIG_NAME M_F_CPU1_SA_DQ<6>
J 0
(-3365 5860);
DISPLAY 0.659574 (-3365 5860);
PAINT MONO (-3365 5860);
DISPLAY INVISIBLE (-3365 5860);
FORCEPROP 1 LASTPIN (-3375 5850) BN 6
J 0
(-3387 5858);
DISPLAY 0.489362 (-3387 5858);
PAINT GREEN (-3387 5858);
FORCEPROP 2 LAST CDS_LIB mstr_standard
J 0
(-3325 5850);
DISPLAY 0.723404 (-3325 5850);
PAINT MONO (-3325 5850);
DISPLAY INVISIBLE (-3325 5850);
FORCEPROP 1 LAST BODY_TYPE PLUMBING
J 0
(-3325 5900);
DISPLAY 0.872340 (-3325 5900);
PAINT GREEN (-3325 5900);
DISPLAY INVISIBLE (-3325 5900);
FORCEPROP 1 LAST HDL_TAP TRUE
J 0
(-3000 5725);
DISPLAY 0.872340 (-3000 5725);
DISPLAY INVISIBLE (-3000 5725);
FORCEPROP 1 LAST PATH I168
J 0
(-3327 5850);
DISPLAY 0.872340 (-3327 5850);
PAINT GREEN (-3327 5850);
DISPLAY INVISIBLE (-3327 5850);
FORCEADD TAP..1
(-3325 5800);
FORCEPROP 3 LASTPIN (-3375 5800) SIG_NAME M_F_CPU1_SA_DQ<7>
J 0
(-3365 5810);
DISPLAY 0.659574 (-3365 5810);
PAINT MONO (-3365 5810);
DISPLAY INVISIBLE (-3365 5810);
FORCEPROP 1 LASTPIN (-3375 5800) BN 7
J 0
(-3387 5808);
DISPLAY 0.489362 (-3387 5808);
PAINT GREEN (-3387 5808);
FORCEPROP 2 LAST CDS_LIB mstr_standard
J 0
(-3325 5800);
DISPLAY 0.723404 (-3325 5800);
PAINT MONO (-3325 5800);
DISPLAY INVISIBLE (-3325 5800);
FORCEPROP 1 LAST BODY_TYPE PLUMBING
J 0
(-3325 5850);
DISPLAY 0.872340 (-3325 5850);
PAINT GREEN (-3325 5850);
DISPLAY INVISIBLE (-3325 5850);
FORCEPROP 1 LAST HDL_TAP TRUE
J 0
(-3000 5675);
DISPLAY 0.872340 (-3000 5675);
DISPLAY INVISIBLE (-3000 5675);
FORCEPROP 1 LAST PATH I169
J 0
(-3327 5800);
DISPLAY 0.872340 (-3327 5800);
PAINT GREEN (-3327 5800);
DISPLAY INVISIBLE (-3327 5800);
FORCEADD TAP..1
(-3325 5700);
FORCEPROP 3 LASTPIN (-3375 5700) SIG_NAME M_F_CPU1_SA_DQ<8>
J 0
(-3365 5710);
DISPLAY 0.659574 (-3365 5710);
PAINT MONO (-3365 5710);
DISPLAY INVISIBLE (-3365 5710);
FORCEPROP 1 LASTPIN (-3375 5700) BN 8
J 0
(-3387 5708);
DISPLAY 0.489362 (-3387 5708);
PAINT GREEN (-3387 5708);
FORCEPROP 2 LAST CDS_LIB mstr_standard
J 0
(-3325 5700);
DISPLAY 0.723404 (-3325 5700);
PAINT MONO (-3325 5700);
DISPLAY INVISIBLE (-3325 5700);
FORCEPROP 1 LAST BODY_TYPE PLUMBING
J 0
(-3325 5750);
DISPLAY 0.872340 (-3325 5750);
PAINT GREEN (-3325 5750);
DISPLAY INVISIBLE (-3325 5750);
FORCEPROP 1 LAST HDL_TAP TRUE
J 0
(-3000 5575);
DISPLAY 0.872340 (-3000 5575);
DISPLAY INVISIBLE (-3000 5575);
FORCEPROP 1 LAST PATH I170
J 0
(-3327 5700);
DISPLAY 0.872340 (-3327 5700);
PAINT GREEN (-3327 5700);
DISPLAY INVISIBLE (-3327 5700);
FORCEADD TAP..1
(-3325 5650);
FORCEPROP 3 LASTPIN (-3375 5650) SIG_NAME M_F_CPU1_SA_DQ<9>
J 0
(-3365 5660);
DISPLAY 0.659574 (-3365 5660);
PAINT MONO (-3365 5660);
DISPLAY INVISIBLE (-3365 5660);
FORCEPROP 1 LASTPIN (-3375 5650) BN 9
J 0
(-3387 5658);
DISPLAY 0.489362 (-3387 5658);
PAINT GREEN (-3387 5658);
FORCEPROP 2 LAST CDS_LIB mstr_standard
J 0
(-3325 5650);
DISPLAY 0.723404 (-3325 5650);
PAINT MONO (-3325 5650);
DISPLAY INVISIBLE (-3325 5650);
FORCEPROP 1 LAST BODY_TYPE PLUMBING
J 0
(-3325 5700);
DISPLAY 0.872340 (-3325 5700);
PAINT GREEN (-3325 5700);
DISPLAY INVISIBLE (-3325 5700);
FORCEPROP 1 LAST HDL_TAP TRUE
J 0
(-3000 5525);
DISPLAY 0.872340 (-3000 5525);
DISPLAY INVISIBLE (-3000 5525);
FORCEPROP 1 LAST PATH I171
J 0
(-3327 5650);
DISPLAY 0.872340 (-3327 5650);
PAINT GREEN (-3327 5650);
DISPLAY INVISIBLE (-3327 5650);
FORCEADD TAP..1
(-3325 5550);
FORCEPROP 3 LASTPIN (-3375 5550) SIG_NAME M_F_CPU1_SA_DQ<11>
J 0
(-3365 5560);
DISPLAY 0.659574 (-3365 5560);
PAINT MONO (-3365 5560);
DISPLAY INVISIBLE (-3365 5560);
FORCEPROP 1 LASTPIN (-3375 5550) BN 11
J 0
(-3387 5558);
DISPLAY 0.489362 (-3387 5558);
PAINT GREEN (-3387 5558);
FORCEPROP 2 LAST CDS_LIB mstr_standard
J 0
(-3325 5550);
DISPLAY 0.723404 (-3325 5550);
PAINT MONO (-3325 5550);
DISPLAY INVISIBLE (-3325 5550);
FORCEPROP 1 LAST BODY_TYPE PLUMBING
J 0
(-3325 5600);
DISPLAY 0.872340 (-3325 5600);
PAINT GREEN (-3325 5600);
DISPLAY INVISIBLE (-3325 5600);
FORCEPROP 1 LAST HDL_TAP TRUE
J 0
(-3000 5425);
DISPLAY 0.872340 (-3000 5425);
DISPLAY INVISIBLE (-3000 5425);
FORCEPROP 1 LAST PATH I172
J 0
(-3327 5550);
DISPLAY 0.872340 (-3327 5550);
PAINT GREEN (-3327 5550);
DISPLAY INVISIBLE (-3327 5550);
FORCEADD TAP..1
(-3325 5600);
FORCEPROP 3 LASTPIN (-3375 5600) SIG_NAME M_F_CPU1_SA_DQ<10>
J 0
(-3365 5610);
DISPLAY 0.659574 (-3365 5610);
PAINT MONO (-3365 5610);
DISPLAY INVISIBLE (-3365 5610);
FORCEPROP 1 LASTPIN (-3375 5600) BN 10
J 0
(-3387 5608);
DISPLAY 0.489362 (-3387 5608);
PAINT GREEN (-3387 5608);
FORCEPROP 2 LAST CDS_LIB mstr_standard
J 0
(-3325 5600);
DISPLAY 0.723404 (-3325 5600);
PAINT MONO (-3325 5600);
DISPLAY INVISIBLE (-3325 5600);
FORCEPROP 1 LAST BODY_TYPE PLUMBING
J 0
(-3325 5650);
DISPLAY 0.872340 (-3325 5650);
PAINT GREEN (-3325 5650);
DISPLAY INVISIBLE (-3325 5650);
FORCEPROP 1 LAST HDL_TAP TRUE
J 0
(-3000 5475);
DISPLAY 0.872340 (-3000 5475);
DISPLAY INVISIBLE (-3000 5475);
FORCEPROP 1 LAST PATH I173
J 0
(-3327 5600);
DISPLAY 0.872340 (-3327 5600);
PAINT GREEN (-3327 5600);
DISPLAY INVISIBLE (-3327 5600);
FORCEADD TAP..1
(-3325 5450);
FORCEPROP 3 LASTPIN (-3375 5450) SIG_NAME M_F_CPU1_SA_DQ<13>
J 0
(-3365 5460);
DISPLAY 0.659574 (-3365 5460);
PAINT MONO (-3365 5460);
DISPLAY INVISIBLE (-3365 5460);
FORCEPROP 1 LASTPIN (-3375 5450) BN 13
J 0
(-3387 5458);
DISPLAY 0.489362 (-3387 5458);
PAINT GREEN (-3387 5458);
FORCEPROP 2 LAST CDS_LIB mstr_standard
J 0
(-3325 5450);
DISPLAY 0.723404 (-3325 5450);
PAINT MONO (-3325 5450);
DISPLAY INVISIBLE (-3325 5450);
FORCEPROP 1 LAST BODY_TYPE PLUMBING
J 0
(-3325 5500);
DISPLAY 0.872340 (-3325 5500);
PAINT GREEN (-3325 5500);
DISPLAY INVISIBLE (-3325 5500);
FORCEPROP 1 LAST HDL_TAP TRUE
J 0
(-3000 5325);
DISPLAY 0.872340 (-3000 5325);
DISPLAY INVISIBLE (-3000 5325);
FORCEPROP 1 LAST PATH I174
J 0
(-3327 5450);
DISPLAY 0.872340 (-3327 5450);
PAINT GREEN (-3327 5450);
DISPLAY INVISIBLE (-3327 5450);
FORCEADD TAP..1
(-3325 5500);
FORCEPROP 3 LASTPIN (-3375 5500) SIG_NAME M_F_CPU1_SA_DQ<12>
J 0
(-3365 5510);
DISPLAY 0.659574 (-3365 5510);
PAINT MONO (-3365 5510);
DISPLAY INVISIBLE (-3365 5510);
FORCEPROP 1 LASTPIN (-3375 5500) BN 12
J 0
(-3387 5508);
DISPLAY 0.489362 (-3387 5508);
PAINT GREEN (-3387 5508);
FORCEPROP 2 LAST CDS_LIB mstr_standard
J 0
(-3325 5500);
DISPLAY 0.723404 (-3325 5500);
PAINT MONO (-3325 5500);
DISPLAY INVISIBLE (-3325 5500);
FORCEPROP 1 LAST BODY_TYPE PLUMBING
J 0
(-3325 5550);
DISPLAY 0.872340 (-3325 5550);
PAINT GREEN (-3325 5550);
DISPLAY INVISIBLE (-3325 5550);
FORCEPROP 1 LAST HDL_TAP TRUE
J 0
(-3000 5375);
DISPLAY 0.872340 (-3000 5375);
DISPLAY INVISIBLE (-3000 5375);
FORCEPROP 1 LAST PATH I175
J 0
(-3327 5500);
DISPLAY 0.872340 (-3327 5500);
PAINT GREEN (-3327 5500);
DISPLAY INVISIBLE (-3327 5500);
FORCEADD TAP..1
(-3325 5400);
FORCEPROP 3 LASTPIN (-3375 5400) SIG_NAME M_F_CPU1_SA_DQ<14>
J 0
(-3365 5410);
DISPLAY 0.659574 (-3365 5410);
PAINT MONO (-3365 5410);
DISPLAY INVISIBLE (-3365 5410);
FORCEPROP 1 LASTPIN (-3375 5400) BN 14
J 0
(-3387 5408);
DISPLAY 0.489362 (-3387 5408);
PAINT GREEN (-3387 5408);
FORCEPROP 2 LAST CDS_LIB mstr_standard
J 0
(-3325 5400);
DISPLAY 0.723404 (-3325 5400);
PAINT MONO (-3325 5400);
DISPLAY INVISIBLE (-3325 5400);
FORCEPROP 1 LAST BODY_TYPE PLUMBING
J 0
(-3325 5450);
DISPLAY 0.872340 (-3325 5450);
PAINT GREEN (-3325 5450);
DISPLAY INVISIBLE (-3325 5450);
FORCEPROP 1 LAST HDL_TAP TRUE
J 0
(-3000 5275);
DISPLAY 0.872340 (-3000 5275);
DISPLAY INVISIBLE (-3000 5275);
FORCEPROP 1 LAST PATH I176
J 0
(-3327 5400);
DISPLAY 0.872340 (-3327 5400);
PAINT GREEN (-3327 5400);
DISPLAY INVISIBLE (-3327 5400);
FORCEADD TAP..1
(-3325 5350);
FORCEPROP 3 LASTPIN (-3375 5350) SIG_NAME M_F_CPU1_SA_DQ<15>
J 0
(-3365 5360);
DISPLAY 0.659574 (-3365 5360);
PAINT MONO (-3365 5360);
DISPLAY INVISIBLE (-3365 5360);
FORCEPROP 1 LASTPIN (-3375 5350) BN 15
J 0
(-3387 5358);
DISPLAY 0.489362 (-3387 5358);
PAINT GREEN (-3387 5358);
FORCEPROP 2 LAST CDS_LIB mstr_standard
J 0
(-3325 5350);
DISPLAY 0.723404 (-3325 5350);
PAINT MONO (-3325 5350);
DISPLAY INVISIBLE (-3325 5350);
FORCEPROP 1 LAST BODY_TYPE PLUMBING
J 0
(-3325 5400);
DISPLAY 0.872340 (-3325 5400);
PAINT GREEN (-3325 5400);
DISPLAY INVISIBLE (-3325 5400);
FORCEPROP 1 LAST HDL_TAP TRUE
J 0
(-3000 5225);
DISPLAY 0.872340 (-3000 5225);
DISPLAY INVISIBLE (-3000 5225);
FORCEPROP 1 LAST PATH I177
J 0
(-3327 5350);
DISPLAY 0.872340 (-3327 5350);
PAINT GREEN (-3327 5350);
DISPLAY INVISIBLE (-3327 5350);
FORCEADD TAP..1
(-3325 5250);
FORCEPROP 3 LASTPIN (-3375 5250) SIG_NAME M_F_CPU1_SA_DQ<16>
J 0
(-3365 5260);
DISPLAY 0.659574 (-3365 5260);
PAINT MONO (-3365 5260);
DISPLAY INVISIBLE (-3365 5260);
FORCEPROP 1 LASTPIN (-3375 5250) BN 16
J 0
(-3387 5258);
DISPLAY 0.489362 (-3387 5258);
PAINT GREEN (-3387 5258);
FORCEPROP 2 LAST CDS_LIB mstr_standard
J 0
(-3325 5250);
DISPLAY 0.723404 (-3325 5250);
PAINT MONO (-3325 5250);
DISPLAY INVISIBLE (-3325 5250);
FORCEPROP 1 LAST BODY_TYPE PLUMBING
J 0
(-3325 5300);
DISPLAY 0.872340 (-3325 5300);
PAINT GREEN (-3325 5300);
DISPLAY INVISIBLE (-3325 5300);
FORCEPROP 1 LAST HDL_TAP TRUE
J 0
(-3000 5125);
DISPLAY 0.872340 (-3000 5125);
DISPLAY INVISIBLE (-3000 5125);
FORCEPROP 1 LAST PATH I178
J 0
(-3327 5250);
DISPLAY 0.872340 (-3327 5250);
PAINT GREEN (-3327 5250);
DISPLAY INVISIBLE (-3327 5250);
FORCEADD TAP..1
(-3325 5200);
FORCEPROP 3 LASTPIN (-3375 5200) SIG_NAME M_F_CPU1_SA_DQ<17>
J 0
(-3365 5210);
DISPLAY 0.659574 (-3365 5210);
PAINT MONO (-3365 5210);
DISPLAY INVISIBLE (-3365 5210);
FORCEPROP 1 LASTPIN (-3375 5200) BN 17
J 0
(-3387 5208);
DISPLAY 0.489362 (-3387 5208);
PAINT GREEN (-3387 5208);
FORCEPROP 2 LAST CDS_LIB mstr_standard
J 0
(-3325 5200);
DISPLAY 0.723404 (-3325 5200);
PAINT MONO (-3325 5200);
DISPLAY INVISIBLE (-3325 5200);
FORCEPROP 1 LAST BODY_TYPE PLUMBING
J 0
(-3325 5250);
DISPLAY 0.872340 (-3325 5250);
PAINT GREEN (-3325 5250);
DISPLAY INVISIBLE (-3325 5250);
FORCEPROP 1 LAST HDL_TAP TRUE
J 0
(-3000 5075);
DISPLAY 0.872340 (-3000 5075);
DISPLAY INVISIBLE (-3000 5075);
FORCEPROP 1 LAST PATH I179
J 0
(-3327 5200);
DISPLAY 0.872340 (-3327 5200);
PAINT GREEN (-3327 5200);
DISPLAY INVISIBLE (-3327 5200);
FORCEADD TAP..1
(-3325 5150);
FORCEPROP 3 LASTPIN (-3375 5150) SIG_NAME M_F_CPU1_SA_DQ<18>
J 0
(-3365 5160);
DISPLAY 0.659574 (-3365 5160);
PAINT MONO (-3365 5160);
DISPLAY INVISIBLE (-3365 5160);
FORCEPROP 1 LASTPIN (-3375 5150) BN 18
J 0
(-3387 5158);
DISPLAY 0.489362 (-3387 5158);
PAINT GREEN (-3387 5158);
FORCEPROP 2 LAST CDS_LIB mstr_standard
J 0
(-3325 5150);
DISPLAY 0.723404 (-3325 5150);
PAINT MONO (-3325 5150);
DISPLAY INVISIBLE (-3325 5150);
FORCEPROP 1 LAST BODY_TYPE PLUMBING
J 0
(-3325 5200);
DISPLAY 0.872340 (-3325 5200);
PAINT GREEN (-3325 5200);
DISPLAY INVISIBLE (-3325 5200);
FORCEPROP 1 LAST HDL_TAP TRUE
J 0
(-3000 5025);
DISPLAY 0.872340 (-3000 5025);
DISPLAY INVISIBLE (-3000 5025);
FORCEPROP 1 LAST PATH I180
J 0
(-3327 5150);
DISPLAY 0.872340 (-3327 5150);
PAINT GREEN (-3327 5150);
DISPLAY INVISIBLE (-3327 5150);
FORCEADD TAP..1
(-3325 5100);
FORCEPROP 3 LASTPIN (-3375 5100) SIG_NAME M_F_CPU1_SA_DQ<19>
J 0
(-3365 5110);
DISPLAY 0.659574 (-3365 5110);
PAINT MONO (-3365 5110);
DISPLAY INVISIBLE (-3365 5110);
FORCEPROP 1 LASTPIN (-3375 5100) BN 19
J 0
(-3387 5108);
DISPLAY 0.489362 (-3387 5108);
PAINT GREEN (-3387 5108);
FORCEPROP 2 LAST CDS_LIB mstr_standard
J 0
(-3325 5100);
DISPLAY 0.723404 (-3325 5100);
PAINT MONO (-3325 5100);
DISPLAY INVISIBLE (-3325 5100);
FORCEPROP 1 LAST BODY_TYPE PLUMBING
J 0
(-3325 5150);
DISPLAY 0.872340 (-3325 5150);
PAINT GREEN (-3325 5150);
DISPLAY INVISIBLE (-3325 5150);
FORCEPROP 1 LAST HDL_TAP TRUE
J 0
(-3000 4975);
DISPLAY 0.872340 (-3000 4975);
DISPLAY INVISIBLE (-3000 4975);
FORCEPROP 1 LAST PATH I181
J 0
(-3327 5100);
DISPLAY 0.872340 (-3327 5100);
PAINT GREEN (-3327 5100);
DISPLAY INVISIBLE (-3327 5100);
FORCEADD TAP..1
(-3325 5050);
FORCEPROP 3 LASTPIN (-3375 5050) SIG_NAME M_F_CPU1_SA_DQ<20>
J 0
(-3365 5060);
DISPLAY 0.659574 (-3365 5060);
PAINT MONO (-3365 5060);
DISPLAY INVISIBLE (-3365 5060);
FORCEPROP 1 LASTPIN (-3375 5050) BN 20
J 0
(-3387 5058);
DISPLAY 0.489362 (-3387 5058);
PAINT GREEN (-3387 5058);
FORCEPROP 2 LAST CDS_LIB mstr_standard
J 0
(-3325 5050);
DISPLAY 0.723404 (-3325 5050);
PAINT MONO (-3325 5050);
DISPLAY INVISIBLE (-3325 5050);
FORCEPROP 1 LAST BODY_TYPE PLUMBING
J 0
(-3325 5100);
DISPLAY 0.872340 (-3325 5100);
PAINT GREEN (-3325 5100);
DISPLAY INVISIBLE (-3325 5100);
FORCEPROP 1 LAST HDL_TAP TRUE
J 0
(-3000 4925);
DISPLAY 0.872340 (-3000 4925);
DISPLAY INVISIBLE (-3000 4925);
FORCEPROP 1 LAST PATH I182
J 0
(-3327 5050);
DISPLAY 0.872340 (-3327 5050);
PAINT GREEN (-3327 5050);
DISPLAY INVISIBLE (-3327 5050);
FORCEADD TAP..1
(-3325 5000);
FORCEPROP 3 LASTPIN (-3375 5000) SIG_NAME M_F_CPU1_SA_DQ<21>
J 0
(-3365 5010);
DISPLAY 0.659574 (-3365 5010);
PAINT MONO (-3365 5010);
DISPLAY INVISIBLE (-3365 5010);
FORCEPROP 1 LASTPIN (-3375 5000) BN 21
J 0
(-3387 5008);
DISPLAY 0.489362 (-3387 5008);
PAINT GREEN (-3387 5008);
FORCEPROP 2 LAST CDS_LIB mstr_standard
J 0
(-3325 5000);
DISPLAY 0.723404 (-3325 5000);
PAINT MONO (-3325 5000);
DISPLAY INVISIBLE (-3325 5000);
FORCEPROP 1 LAST BODY_TYPE PLUMBING
J 0
(-3325 5050);
DISPLAY 0.872340 (-3325 5050);
PAINT GREEN (-3325 5050);
DISPLAY INVISIBLE (-3325 5050);
FORCEPROP 1 LAST HDL_TAP TRUE
J 0
(-3000 4875);
DISPLAY 0.872340 (-3000 4875);
DISPLAY INVISIBLE (-3000 4875);
FORCEPROP 1 LAST PATH I183
J 0
(-3327 5000);
DISPLAY 0.872340 (-3327 5000);
PAINT GREEN (-3327 5000);
DISPLAY INVISIBLE (-3327 5000);
FORCEADD TAP..1
(-3325 4900);
FORCEPROP 3 LASTPIN (-3375 4900) SIG_NAME M_F_CPU1_SA_DQ<23>
J 0
(-3365 4910);
DISPLAY 0.659574 (-3365 4910);
PAINT MONO (-3365 4910);
DISPLAY INVISIBLE (-3365 4910);
FORCEPROP 1 LASTPIN (-3375 4900) BN 23
J 0
(-3387 4908);
DISPLAY 0.489362 (-3387 4908);
PAINT GREEN (-3387 4908);
FORCEPROP 2 LAST CDS_LIB mstr_standard
J 0
(-3325 4900);
DISPLAY 0.723404 (-3325 4900);
PAINT MONO (-3325 4900);
DISPLAY INVISIBLE (-3325 4900);
FORCEPROP 1 LAST BODY_TYPE PLUMBING
J 0
(-3325 4950);
DISPLAY 0.872340 (-3325 4950);
PAINT GREEN (-3325 4950);
DISPLAY INVISIBLE (-3325 4950);
FORCEPROP 1 LAST HDL_TAP TRUE
J 0
(-3000 4775);
DISPLAY 0.872340 (-3000 4775);
DISPLAY INVISIBLE (-3000 4775);
FORCEPROP 1 LAST PATH I184
J 0
(-3327 4900);
DISPLAY 0.872340 (-3327 4900);
PAINT GREEN (-3327 4900);
DISPLAY INVISIBLE (-3327 4900);
FORCEADD TAP..1
(-3325 4950);
FORCEPROP 3 LASTPIN (-3375 4950) SIG_NAME M_F_CPU1_SA_DQ<22>
J 0
(-3365 4960);
DISPLAY 0.659574 (-3365 4960);
PAINT MONO (-3365 4960);
DISPLAY INVISIBLE (-3365 4960);
FORCEPROP 1 LASTPIN (-3375 4950) BN 22
J 0
(-3387 4958);
DISPLAY 0.489362 (-3387 4958);
PAINT GREEN (-3387 4958);
FORCEPROP 2 LAST CDS_LIB mstr_standard
J 0
(-3325 4950);
DISPLAY 0.723404 (-3325 4950);
PAINT MONO (-3325 4950);
DISPLAY INVISIBLE (-3325 4950);
FORCEPROP 1 LAST BODY_TYPE PLUMBING
J 0
(-3325 5000);
DISPLAY 0.872340 (-3325 5000);
PAINT GREEN (-3325 5000);
DISPLAY INVISIBLE (-3325 5000);
FORCEPROP 1 LAST HDL_TAP TRUE
J 0
(-3000 4825);
DISPLAY 0.872340 (-3000 4825);
DISPLAY INVISIBLE (-3000 4825);
FORCEPROP 1 LAST PATH I185
J 0
(-3327 4950);
DISPLAY 0.872340 (-3327 4950);
PAINT GREEN (-3327 4950);
DISPLAY INVISIBLE (-3327 4950);
FORCEADD TAP..1
(-3325 4750);
FORCEPROP 3 LASTPIN (-3375 4750) SIG_NAME M_F_CPU1_SA_DQ<25>
J 0
(-3365 4760);
DISPLAY 0.659574 (-3365 4760);
PAINT MONO (-3365 4760);
DISPLAY INVISIBLE (-3365 4760);
FORCEPROP 1 LASTPIN (-3375 4750) BN 25
J 0
(-3387 4758);
DISPLAY 0.489362 (-3387 4758);
PAINT GREEN (-3387 4758);
FORCEPROP 2 LAST CDS_LIB mstr_standard
J 0
(-3325 4750);
DISPLAY 0.723404 (-3325 4750);
PAINT MONO (-3325 4750);
DISPLAY INVISIBLE (-3325 4750);
FORCEPROP 1 LAST BODY_TYPE PLUMBING
J 0
(-3325 4800);
DISPLAY 0.872340 (-3325 4800);
PAINT GREEN (-3325 4800);
DISPLAY INVISIBLE (-3325 4800);
FORCEPROP 1 LAST HDL_TAP TRUE
J 0
(-3000 4625);
DISPLAY 0.872340 (-3000 4625);
DISPLAY INVISIBLE (-3000 4625);
FORCEPROP 1 LAST PATH I186
J 0
(-3327 4750);
DISPLAY 0.872340 (-3327 4750);
PAINT GREEN (-3327 4750);
DISPLAY INVISIBLE (-3327 4750);
FORCEADD TAP..1
(-3325 4800);
FORCEPROP 3 LASTPIN (-3375 4800) SIG_NAME M_F_CPU1_SA_DQ<24>
J 0
(-3365 4810);
DISPLAY 0.659574 (-3365 4810);
PAINT MONO (-3365 4810);
DISPLAY INVISIBLE (-3365 4810);
FORCEPROP 1 LASTPIN (-3375 4800) BN 24
J 0
(-3387 4808);
DISPLAY 0.489362 (-3387 4808);
PAINT GREEN (-3387 4808);
FORCEPROP 2 LAST CDS_LIB mstr_standard
J 0
(-3325 4800);
DISPLAY 0.723404 (-3325 4800);
PAINT MONO (-3325 4800);
DISPLAY INVISIBLE (-3325 4800);
FORCEPROP 1 LAST BODY_TYPE PLUMBING
J 0
(-3325 4850);
DISPLAY 0.872340 (-3325 4850);
PAINT GREEN (-3325 4850);
DISPLAY INVISIBLE (-3325 4850);
FORCEPROP 1 LAST HDL_TAP TRUE
J 0
(-3000 4675);
DISPLAY 0.872340 (-3000 4675);
DISPLAY INVISIBLE (-3000 4675);
FORCEPROP 1 LAST PATH I187
J 0
(-3327 4800);
DISPLAY 0.872340 (-3327 4800);
PAINT GREEN (-3327 4800);
DISPLAY INVISIBLE (-3327 4800);
FORCEADD TAP..1
(-3325 4700);
FORCEPROP 3 LASTPIN (-3375 4700) SIG_NAME M_F_CPU1_SA_DQ<26>
J 0
(-3365 4710);
DISPLAY 0.659574 (-3365 4710);
PAINT MONO (-3365 4710);
DISPLAY INVISIBLE (-3365 4710);
FORCEPROP 1 LASTPIN (-3375 4700) BN 26
J 0
(-3387 4708);
DISPLAY 0.489362 (-3387 4708);
PAINT GREEN (-3387 4708);
FORCEPROP 2 LAST CDS_LIB mstr_standard
J 0
(-3325 4700);
DISPLAY 0.723404 (-3325 4700);
PAINT MONO (-3325 4700);
DISPLAY INVISIBLE (-3325 4700);
FORCEPROP 1 LAST BODY_TYPE PLUMBING
J 0
(-3325 4750);
DISPLAY 0.872340 (-3325 4750);
PAINT GREEN (-3325 4750);
DISPLAY INVISIBLE (-3325 4750);
FORCEPROP 1 LAST HDL_TAP TRUE
J 0
(-3000 4575);
DISPLAY 0.872340 (-3000 4575);
DISPLAY INVISIBLE (-3000 4575);
FORCEPROP 1 LAST PATH I188
J 0
(-3327 4700);
DISPLAY 0.872340 (-3327 4700);
PAINT GREEN (-3327 4700);
DISPLAY INVISIBLE (-3327 4700);
FORCEADD TAP..1
(-3325 4650);
FORCEPROP 3 LASTPIN (-3375 4650) SIG_NAME M_F_CPU1_SA_DQ<27>
J 0
(-3365 4660);
DISPLAY 0.659574 (-3365 4660);
PAINT MONO (-3365 4660);
DISPLAY INVISIBLE (-3365 4660);
FORCEPROP 1 LASTPIN (-3375 4650) BN 27
J 0
(-3387 4658);
DISPLAY 0.489362 (-3387 4658);
PAINT GREEN (-3387 4658);
FORCEPROP 2 LAST CDS_LIB mstr_standard
J 0
(-3325 4650);
DISPLAY 0.723404 (-3325 4650);
PAINT MONO (-3325 4650);
DISPLAY INVISIBLE (-3325 4650);
FORCEPROP 1 LAST BODY_TYPE PLUMBING
J 0
(-3325 4700);
DISPLAY 0.872340 (-3325 4700);
PAINT GREEN (-3325 4700);
DISPLAY INVISIBLE (-3325 4700);
FORCEPROP 1 LAST HDL_TAP TRUE
J 0
(-3000 4525);
DISPLAY 0.872340 (-3000 4525);
DISPLAY INVISIBLE (-3000 4525);
FORCEPROP 1 LAST PATH I189
J 0
(-3327 4650);
DISPLAY 0.872340 (-3327 4650);
PAINT GREEN (-3327 4650);
DISPLAY INVISIBLE (-3327 4650);
FORCEADD TAP..1
(-3325 4600);
FORCEPROP 3 LASTPIN (-3375 4600) SIG_NAME M_F_CPU1_SA_DQ<28>
J 0
(-3365 4610);
DISPLAY 0.659574 (-3365 4610);
PAINT MONO (-3365 4610);
DISPLAY INVISIBLE (-3365 4610);
FORCEPROP 1 LASTPIN (-3375 4600) BN 28
J 0
(-3387 4608);
DISPLAY 0.489362 (-3387 4608);
PAINT GREEN (-3387 4608);
FORCEPROP 2 LAST CDS_LIB mstr_standard
J 0
(-3325 4600);
DISPLAY 0.723404 (-3325 4600);
PAINT MONO (-3325 4600);
DISPLAY INVISIBLE (-3325 4600);
FORCEPROP 1 LAST BODY_TYPE PLUMBING
J 0
(-3325 4650);
DISPLAY 0.872340 (-3325 4650);
PAINT GREEN (-3325 4650);
DISPLAY INVISIBLE (-3325 4650);
FORCEPROP 1 LAST HDL_TAP TRUE
J 0
(-3000 4475);
DISPLAY 0.872340 (-3000 4475);
DISPLAY INVISIBLE (-3000 4475);
FORCEPROP 1 LAST PATH I190
J 0
(-3327 4600);
DISPLAY 0.872340 (-3327 4600);
PAINT GREEN (-3327 4600);
DISPLAY INVISIBLE (-3327 4600);
FORCEADD TAP..1
(-3325 4500);
FORCEPROP 3 LASTPIN (-3375 4500) SIG_NAME M_F_CPU1_SA_DQ<30>
J 0
(-3365 4510);
DISPLAY 0.659574 (-3365 4510);
PAINT MONO (-3365 4510);
DISPLAY INVISIBLE (-3365 4510);
FORCEPROP 1 LASTPIN (-3375 4500) BN 30
J 0
(-3387 4508);
DISPLAY 0.489362 (-3387 4508);
PAINT GREEN (-3387 4508);
FORCEPROP 2 LAST CDS_LIB mstr_standard
J 0
(-3325 4500);
DISPLAY 0.723404 (-3325 4500);
PAINT MONO (-3325 4500);
DISPLAY INVISIBLE (-3325 4500);
FORCEPROP 1 LAST BODY_TYPE PLUMBING
J 0
(-3325 4550);
DISPLAY 0.872340 (-3325 4550);
PAINT GREEN (-3325 4550);
DISPLAY INVISIBLE (-3325 4550);
FORCEPROP 1 LAST HDL_TAP TRUE
J 0
(-3000 4375);
DISPLAY 0.872340 (-3000 4375);
DISPLAY INVISIBLE (-3000 4375);
FORCEPROP 1 LAST PATH I191
J 0
(-3327 4500);
DISPLAY 0.872340 (-3327 4500);
PAINT GREEN (-3327 4500);
DISPLAY INVISIBLE (-3327 4500);
FORCEADD TAP..1
(-3325 4550);
FORCEPROP 3 LASTPIN (-3375 4550) SIG_NAME M_F_CPU1_SA_DQ<29>
J 0
(-3365 4560);
DISPLAY 0.659574 (-3365 4560);
PAINT MONO (-3365 4560);
DISPLAY INVISIBLE (-3365 4560);
FORCEPROP 1 LASTPIN (-3375 4550) BN 29
J 0
(-3387 4558);
DISPLAY 0.489362 (-3387 4558);
PAINT GREEN (-3387 4558);
FORCEPROP 2 LAST CDS_LIB mstr_standard
J 0
(-3325 4550);
DISPLAY 0.723404 (-3325 4550);
PAINT MONO (-3325 4550);
DISPLAY INVISIBLE (-3325 4550);
FORCEPROP 1 LAST BODY_TYPE PLUMBING
J 0
(-3325 4600);
DISPLAY 0.872340 (-3325 4600);
PAINT GREEN (-3325 4600);
DISPLAY INVISIBLE (-3325 4600);
FORCEPROP 1 LAST HDL_TAP TRUE
J 0
(-3000 4425);
DISPLAY 0.872340 (-3000 4425);
DISPLAY INVISIBLE (-3000 4425);
FORCEPROP 1 LAST PATH I192
J 0
(-3327 4550);
DISPLAY 0.872340 (-3327 4550);
PAINT GREEN (-3327 4550);
DISPLAY INVISIBLE (-3327 4550);
FORCEADD TAP..1
(-3325 4450);
FORCEPROP 3 LASTPIN (-3375 4450) SIG_NAME M_F_CPU1_SA_DQ<31>
J 0
(-3365 4460);
DISPLAY 0.659574 (-3365 4460);
PAINT MONO (-3365 4460);
DISPLAY INVISIBLE (-3365 4460);
FORCEPROP 1 LASTPIN (-3375 4450) BN 31
J 0
(-3387 4458);
DISPLAY 0.489362 (-3387 4458);
PAINT GREEN (-3387 4458);
FORCEPROP 2 LAST CDS_LIB mstr_standard
J 0
(-3325 4450);
DISPLAY 0.723404 (-3325 4450);
PAINT MONO (-3325 4450);
DISPLAY INVISIBLE (-3325 4450);
FORCEPROP 1 LAST BODY_TYPE PLUMBING
J 0
(-3325 4500);
DISPLAY 0.872340 (-3325 4500);
PAINT GREEN (-3325 4500);
DISPLAY INVISIBLE (-3325 4500);
FORCEPROP 1 LAST HDL_TAP TRUE
J 0
(-3000 4325);
DISPLAY 0.872340 (-3000 4325);
DISPLAY INVISIBLE (-3000 4325);
FORCEPROP 1 LAST PATH I193
J 0
(-3327 4450);
DISPLAY 0.872340 (-3327 4450);
PAINT GREEN (-3327 4450);
DISPLAY INVISIBLE (-3327 4450);
FORCEADD TAP..1
(-3325 4350);
FORCEPROP 3 LASTPIN (-3375 4350) SIG_NAME M_F_CPU1_SB_DQ<0>
J 0
(-3365 4360);
DISPLAY 0.659574 (-3365 4360);
PAINT MONO (-3365 4360);
DISPLAY INVISIBLE (-3365 4360);
FORCEPROP 1 LASTPIN (-3375 4350) BN 0
J 0
(-3387 4358);
DISPLAY 0.489362 (-3387 4358);
PAINT GREEN (-3387 4358);
FORCEPROP 2 LAST CDS_LIB mstr_standard
J 0
(-3325 4350);
DISPLAY 0.723404 (-3325 4350);
PAINT MONO (-3325 4350);
DISPLAY INVISIBLE (-3325 4350);
FORCEPROP 1 LAST BODY_TYPE PLUMBING
J 0
(-3325 4400);
DISPLAY 0.872340 (-3325 4400);
PAINT GREEN (-3325 4400);
DISPLAY INVISIBLE (-3325 4400);
FORCEPROP 1 LAST HDL_TAP TRUE
J 0
(-3000 4225);
DISPLAY 0.872340 (-3000 4225);
DISPLAY INVISIBLE (-3000 4225);
FORCEPROP 1 LAST PATH I194
J 0
(-3327 4350);
DISPLAY 0.872340 (-3327 4350);
PAINT GREEN (-3327 4350);
DISPLAY INVISIBLE (-3327 4350);
FORCEADD TAP..1
(-3325 4300);
FORCEPROP 3 LASTPIN (-3375 4300) SIG_NAME M_F_CPU1_SB_DQ<1>
J 0
(-3365 4310);
DISPLAY 0.659574 (-3365 4310);
PAINT MONO (-3365 4310);
DISPLAY INVISIBLE (-3365 4310);
FORCEPROP 1 LASTPIN (-3375 4300) BN 1
J 0
(-3387 4308);
DISPLAY 0.489362 (-3387 4308);
PAINT GREEN (-3387 4308);
FORCEPROP 2 LAST CDS_LIB mstr_standard
J 0
(-3325 4300);
DISPLAY 0.723404 (-3325 4300);
PAINT MONO (-3325 4300);
DISPLAY INVISIBLE (-3325 4300);
FORCEPROP 1 LAST BODY_TYPE PLUMBING
J 0
(-3325 4350);
DISPLAY 0.872340 (-3325 4350);
PAINT GREEN (-3325 4350);
DISPLAY INVISIBLE (-3325 4350);
FORCEPROP 1 LAST HDL_TAP TRUE
J 0
(-3000 4175);
DISPLAY 0.872340 (-3000 4175);
DISPLAY INVISIBLE (-3000 4175);
FORCEPROP 1 LAST PATH I195
J 0
(-3327 4300);
DISPLAY 0.872340 (-3327 4300);
PAINT GREEN (-3327 4300);
DISPLAY INVISIBLE (-3327 4300);
FORCEADD TAP..1
(-3325 4250);
FORCEPROP 3 LASTPIN (-3375 4250) SIG_NAME M_F_CPU1_SB_DQ<2>
J 0
(-3365 4260);
DISPLAY 0.659574 (-3365 4260);
PAINT MONO (-3365 4260);
DISPLAY INVISIBLE (-3365 4260);
FORCEPROP 1 LASTPIN (-3375 4250) BN 2
J 0
(-3387 4258);
DISPLAY 0.489362 (-3387 4258);
PAINT GREEN (-3387 4258);
FORCEPROP 2 LAST CDS_LIB mstr_standard
J 0
(-3325 4250);
DISPLAY 0.723404 (-3325 4250);
PAINT MONO (-3325 4250);
DISPLAY INVISIBLE (-3325 4250);
FORCEPROP 1 LAST BODY_TYPE PLUMBING
J 0
(-3325 4300);
DISPLAY 0.872340 (-3325 4300);
PAINT GREEN (-3325 4300);
DISPLAY INVISIBLE (-3325 4300);
FORCEPROP 1 LAST HDL_TAP TRUE
J 0
(-3000 4125);
DISPLAY 0.872340 (-3000 4125);
DISPLAY INVISIBLE (-3000 4125);
FORCEPROP 1 LAST PATH I196
J 0
(-3327 4250);
DISPLAY 0.872340 (-3327 4250);
PAINT GREEN (-3327 4250);
DISPLAY INVISIBLE (-3327 4250);
FORCEADD TAP..1
(-3325 4150);
FORCEPROP 3 LASTPIN (-3375 4150) SIG_NAME M_F_CPU1_SB_DQ<4>
J 0
(-3365 4160);
DISPLAY 0.659574 (-3365 4160);
PAINT MONO (-3365 4160);
DISPLAY INVISIBLE (-3365 4160);
FORCEPROP 1 LASTPIN (-3375 4150) BN 4
J 0
(-3387 4158);
DISPLAY 0.489362 (-3387 4158);
PAINT GREEN (-3387 4158);
FORCEPROP 2 LAST CDS_LIB mstr_standard
J 0
(-3325 4150);
DISPLAY 0.723404 (-3325 4150);
PAINT MONO (-3325 4150);
DISPLAY INVISIBLE (-3325 4150);
FORCEPROP 1 LAST BODY_TYPE PLUMBING
J 0
(-3325 4200);
DISPLAY 0.872340 (-3325 4200);
PAINT GREEN (-3325 4200);
DISPLAY INVISIBLE (-3325 4200);
FORCEPROP 1 LAST HDL_TAP TRUE
J 0
(-3000 4025);
DISPLAY 0.872340 (-3000 4025);
DISPLAY INVISIBLE (-3000 4025);
FORCEPROP 1 LAST PATH I197
J 0
(-3327 4150);
DISPLAY 0.872340 (-3327 4150);
PAINT GREEN (-3327 4150);
DISPLAY INVISIBLE (-3327 4150);
FORCEADD TAP..1
(-3325 4200);
FORCEPROP 3 LASTPIN (-3375 4200) SIG_NAME M_F_CPU1_SB_DQ<3>
J 0
(-3365 4210);
DISPLAY 0.659574 (-3365 4210);
PAINT MONO (-3365 4210);
DISPLAY INVISIBLE (-3365 4210);
FORCEPROP 1 LASTPIN (-3375 4200) BN 3
J 0
(-3387 4208);
DISPLAY 0.489362 (-3387 4208);
PAINT GREEN (-3387 4208);
FORCEPROP 2 LAST CDS_LIB mstr_standard
J 0
(-3325 4200);
DISPLAY 0.723404 (-3325 4200);
PAINT MONO (-3325 4200);
DISPLAY INVISIBLE (-3325 4200);
FORCEPROP 1 LAST BODY_TYPE PLUMBING
J 0
(-3325 4250);
DISPLAY 0.872340 (-3325 4250);
PAINT GREEN (-3325 4250);
DISPLAY INVISIBLE (-3325 4250);
FORCEPROP 1 LAST HDL_TAP TRUE
J 0
(-3000 4075);
DISPLAY 0.872340 (-3000 4075);
DISPLAY INVISIBLE (-3000 4075);
FORCEPROP 1 LAST PATH I198
J 0
(-3327 4200);
DISPLAY 0.872340 (-3327 4200);
PAINT GREEN (-3327 4200);
DISPLAY INVISIBLE (-3327 4200);
FORCEADD TAP..1
(-3325 4100);
FORCEPROP 3 LASTPIN (-3375 4100) SIG_NAME M_F_CPU1_SB_DQ<5>
J 0
(-3365 4110);
DISPLAY 0.659574 (-3365 4110);
PAINT MONO (-3365 4110);
DISPLAY INVISIBLE (-3365 4110);
FORCEPROP 1 LASTPIN (-3375 4100) BN 5
J 0
(-3387 4108);
DISPLAY 0.489362 (-3387 4108);
PAINT GREEN (-3387 4108);
FORCEPROP 2 LAST CDS_LIB mstr_standard
J 0
(-3325 4100);
DISPLAY 0.723404 (-3325 4100);
PAINT MONO (-3325 4100);
DISPLAY INVISIBLE (-3325 4100);
FORCEPROP 1 LAST BODY_TYPE PLUMBING
J 0
(-3325 4150);
DISPLAY 0.872340 (-3325 4150);
PAINT GREEN (-3325 4150);
DISPLAY INVISIBLE (-3325 4150);
FORCEPROP 1 LAST HDL_TAP TRUE
J 0
(-3000 3975);
DISPLAY 0.872340 (-3000 3975);
DISPLAY INVISIBLE (-3000 3975);
FORCEPROP 1 LAST PATH I199
J 0
(-3327 4100);
DISPLAY 0.872340 (-3327 4100);
PAINT GREEN (-3327 4100);
DISPLAY INVISIBLE (-3327 4100);
FORCEADD OFFPAGE..6
R 2
(-2725 2600);
FORCEPROP 2 LAST $XR0 102 
J 0
(-2511 2600);
DISPLAY 0.638298 (-2511 2600);
PAINT MONO (-2511 2600);
FORCEPROP 2 LAST PATH I200
J 0
(-2500 2650);
DISPLAY 1.021277 (-2500 2650);
DISPLAY INVISIBLE (-2500 2650);
FORCEPROP 1 LAST COMMENT_BODY TRUE
J 2
(-2825 2525);
DISPLAY 0.872340 (-2825 2525);
PAINT GREEN (-2825 2525);
DISPLAY INVISIBLE (-2825 2525);
FORCEPROP 1 LAST OFFPAGE TRUE
J 2
(-3050 2475);
DISPLAY 0.872340 (-3050 2475);
PAINT GREEN (-3050 2475);
DISPLAY INVISIBLE (-3050 2475);
FORCEPROP 2 LAST CDS_LIB mstr_standard
J 2
(-2725 2600);
DISPLAY 0.723404 (-2725 2600);
PAINT MONO (-2725 2600);
DISPLAY INVISIBLE (-2725 2600);
FORCEADD OFFPAGE..6
R 2
(-2725 2150);
FORCEPROP 2 LAST $XR0 102 
J 0
(-2511 2150);
DISPLAY 0.638298 (-2511 2150);
PAINT MONO (-2511 2150);
FORCEPROP 2 LAST PATH I201
J 0
(-2500 2200);
DISPLAY 1.021277 (-2500 2200);
DISPLAY INVISIBLE (-2500 2200);
FORCEPROP 1 LAST COMMENT_BODY TRUE
J 2
(-2825 2075);
DISPLAY 0.872340 (-2825 2075);
PAINT GREEN (-2825 2075);
DISPLAY INVISIBLE (-2825 2075);
FORCEPROP 1 LAST OFFPAGE TRUE
J 2
(-3050 2025);
DISPLAY 0.872340 (-3050 2025);
PAINT GREEN (-3050 2025);
DISPLAY INVISIBLE (-3050 2025);
FORCEPROP 2 LAST CDS_LIB mstr_standard
J 2
(-2725 2150);
DISPLAY 0.723404 (-2725 2150);
PAINT MONO (-2725 2150);
DISPLAY INVISIBLE (-2725 2150);
FORCEADD TAP..1
(-3325 4000);
FORCEPROP 3 LASTPIN (-3375 4000) SIG_NAME M_F_CPU1_SB_DQ<7>
J 0
(-3365 4010);
DISPLAY 0.659574 (-3365 4010);
PAINT MONO (-3365 4010);
DISPLAY INVISIBLE (-3365 4010);
FORCEPROP 1 LASTPIN (-3375 4000) BN 7
J 0
(-3387 4008);
DISPLAY 0.489362 (-3387 4008);
PAINT GREEN (-3387 4008);
FORCEPROP 2 LAST CDS_LIB mstr_standard
J 0
(-3325 4000);
DISPLAY 0.723404 (-3325 4000);
PAINT MONO (-3325 4000);
DISPLAY INVISIBLE (-3325 4000);
FORCEPROP 1 LAST BODY_TYPE PLUMBING
J 0
(-3325 4050);
DISPLAY 0.872340 (-3325 4050);
PAINT GREEN (-3325 4050);
DISPLAY INVISIBLE (-3325 4050);
FORCEPROP 1 LAST HDL_TAP TRUE
J 0
(-3000 3875);
DISPLAY 0.872340 (-3000 3875);
DISPLAY INVISIBLE (-3000 3875);
FORCEPROP 1 LAST PATH I202
J 0
(-3327 4000);
DISPLAY 0.872340 (-3327 4000);
PAINT GREEN (-3327 4000);
DISPLAY INVISIBLE (-3327 4000);
FORCEADD TAP..1
(-3325 4050);
FORCEPROP 3 LASTPIN (-3375 4050) SIG_NAME M_F_CPU1_SB_DQ<6>
J 0
(-3365 4060);
DISPLAY 0.659574 (-3365 4060);
PAINT MONO (-3365 4060);
DISPLAY INVISIBLE (-3365 4060);
FORCEPROP 1 LASTPIN (-3375 4050) BN 6
J 0
(-3387 4058);
DISPLAY 0.489362 (-3387 4058);
PAINT GREEN (-3387 4058);
FORCEPROP 2 LAST CDS_LIB mstr_standard
J 0
(-3325 4050);
DISPLAY 0.723404 (-3325 4050);
PAINT MONO (-3325 4050);
DISPLAY INVISIBLE (-3325 4050);
FORCEPROP 1 LAST BODY_TYPE PLUMBING
J 0
(-3325 4100);
DISPLAY 0.872340 (-3325 4100);
PAINT GREEN (-3325 4100);
DISPLAY INVISIBLE (-3325 4100);
FORCEPROP 1 LAST HDL_TAP TRUE
J 0
(-3000 3925);
DISPLAY 0.872340 (-3000 3925);
DISPLAY INVISIBLE (-3000 3925);
FORCEPROP 1 LAST PATH I203
J 0
(-3327 4050);
DISPLAY 0.872340 (-3327 4050);
PAINT GREEN (-3327 4050);
DISPLAY INVISIBLE (-3327 4050);
FORCEADD TAP..1
(-3325 3850);
FORCEPROP 3 LASTPIN (-3375 3850) SIG_NAME M_F_CPU1_SB_DQ<9>
J 0
(-3365 3860);
DISPLAY 0.659574 (-3365 3860);
PAINT MONO (-3365 3860);
DISPLAY INVISIBLE (-3365 3860);
FORCEPROP 1 LASTPIN (-3375 3850) BN 9
J 0
(-3387 3858);
DISPLAY 0.489362 (-3387 3858);
PAINT GREEN (-3387 3858);
FORCEPROP 2 LAST CDS_LIB mstr_standard
J 0
(-3325 3850);
DISPLAY 0.723404 (-3325 3850);
PAINT MONO (-3325 3850);
DISPLAY INVISIBLE (-3325 3850);
FORCEPROP 1 LAST BODY_TYPE PLUMBING
J 0
(-3325 3900);
DISPLAY 0.872340 (-3325 3900);
PAINT GREEN (-3325 3900);
DISPLAY INVISIBLE (-3325 3900);
FORCEPROP 1 LAST HDL_TAP TRUE
J 0
(-3000 3725);
DISPLAY 0.872340 (-3000 3725);
DISPLAY INVISIBLE (-3000 3725);
FORCEPROP 1 LAST PATH I204
J 0
(-3327 3850);
DISPLAY 0.872340 (-3327 3850);
PAINT GREEN (-3327 3850);
DISPLAY INVISIBLE (-3327 3850);
FORCEADD TAP..1
(-3325 3900);
FORCEPROP 3 LASTPIN (-3375 3900) SIG_NAME M_F_CPU1_SB_DQ<8>
J 0
(-3365 3910);
DISPLAY 0.659574 (-3365 3910);
PAINT MONO (-3365 3910);
DISPLAY INVISIBLE (-3365 3910);
FORCEPROP 1 LASTPIN (-3375 3900) BN 8
J 0
(-3387 3908);
DISPLAY 0.489362 (-3387 3908);
PAINT GREEN (-3387 3908);
FORCEPROP 2 LAST CDS_LIB mstr_standard
J 0
(-3325 3900);
DISPLAY 0.723404 (-3325 3900);
PAINT MONO (-3325 3900);
DISPLAY INVISIBLE (-3325 3900);
FORCEPROP 1 LAST BODY_TYPE PLUMBING
J 0
(-3325 3950);
DISPLAY 0.872340 (-3325 3950);
PAINT GREEN (-3325 3950);
DISPLAY INVISIBLE (-3325 3950);
FORCEPROP 1 LAST HDL_TAP TRUE
J 0
(-3000 3775);
DISPLAY 0.872340 (-3000 3775);
DISPLAY INVISIBLE (-3000 3775);
FORCEPROP 1 LAST PATH I205
J 0
(-3327 3900);
DISPLAY 0.872340 (-3327 3900);
PAINT GREEN (-3327 3900);
DISPLAY INVISIBLE (-3327 3900);
FORCEADD TAP..1
(-3325 3800);
FORCEPROP 3 LASTPIN (-3375 3800) SIG_NAME M_F_CPU1_SB_DQ<10>
J 0
(-3365 3810);
DISPLAY 0.659574 (-3365 3810);
PAINT MONO (-3365 3810);
DISPLAY INVISIBLE (-3365 3810);
FORCEPROP 1 LASTPIN (-3375 3800) BN 10
J 0
(-3387 3808);
DISPLAY 0.489362 (-3387 3808);
PAINT GREEN (-3387 3808);
FORCEPROP 2 LAST CDS_LIB mstr_standard
J 0
(-3325 3800);
DISPLAY 0.723404 (-3325 3800);
PAINT MONO (-3325 3800);
DISPLAY INVISIBLE (-3325 3800);
FORCEPROP 1 LAST BODY_TYPE PLUMBING
J 0
(-3325 3850);
DISPLAY 0.872340 (-3325 3850);
PAINT GREEN (-3325 3850);
DISPLAY INVISIBLE (-3325 3850);
FORCEPROP 1 LAST HDL_TAP TRUE
J 0
(-3000 3675);
DISPLAY 0.872340 (-3000 3675);
DISPLAY INVISIBLE (-3000 3675);
FORCEPROP 1 LAST PATH I206
J 0
(-3327 3800);
DISPLAY 0.872340 (-3327 3800);
PAINT GREEN (-3327 3800);
DISPLAY INVISIBLE (-3327 3800);
FORCEADD TAP..1
(-3325 3750);
FORCEPROP 3 LASTPIN (-3375 3750) SIG_NAME M_F_CPU1_SB_DQ<11>
J 0
(-3365 3760);
DISPLAY 0.659574 (-3365 3760);
PAINT MONO (-3365 3760);
DISPLAY INVISIBLE (-3365 3760);
FORCEPROP 1 LASTPIN (-3375 3750) BN 11
J 0
(-3387 3758);
DISPLAY 0.489362 (-3387 3758);
PAINT GREEN (-3387 3758);
FORCEPROP 2 LAST CDS_LIB mstr_standard
J 0
(-3325 3750);
DISPLAY 0.723404 (-3325 3750);
PAINT MONO (-3325 3750);
DISPLAY INVISIBLE (-3325 3750);
FORCEPROP 1 LAST BODY_TYPE PLUMBING
J 0
(-3325 3800);
DISPLAY 0.872340 (-3325 3800);
PAINT GREEN (-3325 3800);
DISPLAY INVISIBLE (-3325 3800);
FORCEPROP 1 LAST HDL_TAP TRUE
J 0
(-3000 3625);
DISPLAY 0.872340 (-3000 3625);
DISPLAY INVISIBLE (-3000 3625);
FORCEPROP 1 LAST PATH I207
J 0
(-3327 3750);
DISPLAY 0.872340 (-3327 3750);
PAINT GREEN (-3327 3750);
DISPLAY INVISIBLE (-3327 3750);
FORCEADD TAP..1
(-3325 3600);
FORCEPROP 3 LASTPIN (-3375 3600) SIG_NAME M_F_CPU1_SB_DQ<14>
J 0
(-3365 3610);
DISPLAY 0.659574 (-3365 3610);
PAINT MONO (-3365 3610);
DISPLAY INVISIBLE (-3365 3610);
FORCEPROP 1 LASTPIN (-3375 3600) BN 14
J 0
(-3387 3608);
DISPLAY 0.489362 (-3387 3608);
PAINT GREEN (-3387 3608);
FORCEPROP 2 LAST CDS_LIB mstr_standard
J 0
(-3325 3600);
DISPLAY 0.723404 (-3325 3600);
PAINT MONO (-3325 3600);
DISPLAY INVISIBLE (-3325 3600);
FORCEPROP 1 LAST BODY_TYPE PLUMBING
J 0
(-3325 3650);
DISPLAY 0.872340 (-3325 3650);
PAINT GREEN (-3325 3650);
DISPLAY INVISIBLE (-3325 3650);
FORCEPROP 1 LAST HDL_TAP TRUE
J 0
(-3000 3475);
DISPLAY 0.872340 (-3000 3475);
DISPLAY INVISIBLE (-3000 3475);
FORCEPROP 1 LAST PATH I208
J 0
(-3327 3600);
DISPLAY 0.872340 (-3327 3600);
PAINT GREEN (-3327 3600);
DISPLAY INVISIBLE (-3327 3600);
FORCEADD TAP..1
(-3325 3700);
FORCEPROP 3 LASTPIN (-3375 3700) SIG_NAME M_F_CPU1_SB_DQ<12>
J 0
(-3365 3710);
DISPLAY 0.659574 (-3365 3710);
PAINT MONO (-3365 3710);
DISPLAY INVISIBLE (-3365 3710);
FORCEPROP 1 LASTPIN (-3375 3700) BN 12
J 0
(-3387 3708);
DISPLAY 0.489362 (-3387 3708);
PAINT GREEN (-3387 3708);
FORCEPROP 2 LAST CDS_LIB mstr_standard
J 0
(-3325 3700);
DISPLAY 0.723404 (-3325 3700);
PAINT MONO (-3325 3700);
DISPLAY INVISIBLE (-3325 3700);
FORCEPROP 1 LAST BODY_TYPE PLUMBING
J 0
(-3325 3750);
DISPLAY 0.872340 (-3325 3750);
PAINT GREEN (-3325 3750);
DISPLAY INVISIBLE (-3325 3750);
FORCEPROP 1 LAST HDL_TAP TRUE
J 0
(-3000 3575);
DISPLAY 0.872340 (-3000 3575);
DISPLAY INVISIBLE (-3000 3575);
FORCEPROP 1 LAST PATH I209
J 0
(-3327 3700);
DISPLAY 0.872340 (-3327 3700);
PAINT GREEN (-3327 3700);
DISPLAY INVISIBLE (-3327 3700);
FORCEADD TAP..1
(-3325 3650);
FORCEPROP 3 LASTPIN (-3375 3650) SIG_NAME M_F_CPU1_SB_DQ<13>
J 0
(-3365 3660);
DISPLAY 0.659574 (-3365 3660);
PAINT MONO (-3365 3660);
DISPLAY INVISIBLE (-3365 3660);
FORCEPROP 1 LASTPIN (-3375 3650) BN 13
J 0
(-3387 3658);
DISPLAY 0.489362 (-3387 3658);
PAINT GREEN (-3387 3658);
FORCEPROP 2 LAST CDS_LIB mstr_standard
J 0
(-3325 3650);
DISPLAY 0.723404 (-3325 3650);
PAINT MONO (-3325 3650);
DISPLAY INVISIBLE (-3325 3650);
FORCEPROP 1 LAST BODY_TYPE PLUMBING
J 0
(-3325 3700);
DISPLAY 0.872340 (-3325 3700);
PAINT GREEN (-3325 3700);
DISPLAY INVISIBLE (-3325 3700);
FORCEPROP 1 LAST HDL_TAP TRUE
J 0
(-3000 3525);
DISPLAY 0.872340 (-3000 3525);
DISPLAY INVISIBLE (-3000 3525);
FORCEPROP 1 LAST PATH I210
J 0
(-3327 3650);
DISPLAY 0.872340 (-3327 3650);
PAINT GREEN (-3327 3650);
DISPLAY INVISIBLE (-3327 3650);
FORCEADD TAP..1
(-3325 3550);
FORCEPROP 3 LASTPIN (-3375 3550) SIG_NAME M_F_CPU1_SB_DQ<15>
J 0
(-3365 3560);
DISPLAY 0.659574 (-3365 3560);
PAINT MONO (-3365 3560);
DISPLAY INVISIBLE (-3365 3560);
FORCEPROP 1 LASTPIN (-3375 3550) BN 15
J 0
(-3387 3558);
DISPLAY 0.489362 (-3387 3558);
PAINT GREEN (-3387 3558);
FORCEPROP 2 LAST CDS_LIB mstr_standard
J 0
(-3325 3550);
DISPLAY 0.723404 (-3325 3550);
PAINT MONO (-3325 3550);
DISPLAY INVISIBLE (-3325 3550);
FORCEPROP 1 LAST BODY_TYPE PLUMBING
J 0
(-3325 3600);
DISPLAY 0.872340 (-3325 3600);
PAINT GREEN (-3325 3600);
DISPLAY INVISIBLE (-3325 3600);
FORCEPROP 1 LAST HDL_TAP TRUE
J 0
(-3000 3425);
DISPLAY 0.872340 (-3000 3425);
DISPLAY INVISIBLE (-3000 3425);
FORCEPROP 1 LAST PATH I211
J 0
(-3327 3550);
DISPLAY 0.872340 (-3327 3550);
PAINT GREEN (-3327 3550);
DISPLAY INVISIBLE (-3327 3550);
FORCEADD TAP..1
(-3325 3450);
FORCEPROP 3 LASTPIN (-3375 3450) SIG_NAME M_F_CPU1_SB_DQ<16>
J 0
(-3365 3460);
DISPLAY 0.659574 (-3365 3460);
PAINT MONO (-3365 3460);
DISPLAY INVISIBLE (-3365 3460);
FORCEPROP 1 LASTPIN (-3375 3450) BN 16
J 0
(-3387 3458);
DISPLAY 0.489362 (-3387 3458);
PAINT GREEN (-3387 3458);
FORCEPROP 2 LAST CDS_LIB mstr_standard
J 0
(-3325 3450);
DISPLAY 0.723404 (-3325 3450);
PAINT MONO (-3325 3450);
DISPLAY INVISIBLE (-3325 3450);
FORCEPROP 1 LAST BODY_TYPE PLUMBING
J 0
(-3325 3500);
DISPLAY 0.872340 (-3325 3500);
PAINT GREEN (-3325 3500);
DISPLAY INVISIBLE (-3325 3500);
FORCEPROP 1 LAST HDL_TAP TRUE
J 0
(-3000 3325);
DISPLAY 0.872340 (-3000 3325);
DISPLAY INVISIBLE (-3000 3325);
FORCEPROP 1 LAST PATH I212
J 0
(-3327 3450);
DISPLAY 0.872340 (-3327 3450);
PAINT GREEN (-3327 3450);
DISPLAY INVISIBLE (-3327 3450);
FORCEADD TAP..1
(-3325 3400);
FORCEPROP 3 LASTPIN (-3375 3400) SIG_NAME M_F_CPU1_SB_DQ<17>
J 0
(-3365 3410);
DISPLAY 0.659574 (-3365 3410);
PAINT MONO (-3365 3410);
DISPLAY INVISIBLE (-3365 3410);
FORCEPROP 1 LASTPIN (-3375 3400) BN 17
J 0
(-3387 3408);
DISPLAY 0.489362 (-3387 3408);
PAINT GREEN (-3387 3408);
FORCEPROP 2 LAST CDS_LIB mstr_standard
J 0
(-3325 3400);
DISPLAY 0.723404 (-3325 3400);
PAINT MONO (-3325 3400);
DISPLAY INVISIBLE (-3325 3400);
FORCEPROP 1 LAST BODY_TYPE PLUMBING
J 0
(-3325 3450);
DISPLAY 0.872340 (-3325 3450);
PAINT GREEN (-3325 3450);
DISPLAY INVISIBLE (-3325 3450);
FORCEPROP 1 LAST HDL_TAP TRUE
J 0
(-3000 3275);
DISPLAY 0.872340 (-3000 3275);
DISPLAY INVISIBLE (-3000 3275);
FORCEPROP 1 LAST PATH I213
J 0
(-3327 3400);
DISPLAY 0.872340 (-3327 3400);
PAINT GREEN (-3327 3400);
DISPLAY INVISIBLE (-3327 3400);
FORCEADD TAP..1
(-3325 3350);
FORCEPROP 3 LASTPIN (-3375 3350) SIG_NAME M_F_CPU1_SB_DQ<18>
J 0
(-3365 3360);
DISPLAY 0.659574 (-3365 3360);
PAINT MONO (-3365 3360);
DISPLAY INVISIBLE (-3365 3360);
FORCEPROP 1 LASTPIN (-3375 3350) BN 18
J 0
(-3387 3358);
DISPLAY 0.489362 (-3387 3358);
PAINT GREEN (-3387 3358);
FORCEPROP 2 LAST CDS_LIB mstr_standard
J 0
(-3325 3350);
DISPLAY 0.723404 (-3325 3350);
PAINT MONO (-3325 3350);
DISPLAY INVISIBLE (-3325 3350);
FORCEPROP 1 LAST BODY_TYPE PLUMBING
J 0
(-3325 3400);
DISPLAY 0.872340 (-3325 3400);
PAINT GREEN (-3325 3400);
DISPLAY INVISIBLE (-3325 3400);
FORCEPROP 1 LAST HDL_TAP TRUE
J 0
(-3000 3225);
DISPLAY 0.872340 (-3000 3225);
DISPLAY INVISIBLE (-3000 3225);
FORCEPROP 1 LAST PATH I214
J 0
(-3327 3350);
DISPLAY 0.872340 (-3327 3350);
PAINT GREEN (-3327 3350);
DISPLAY INVISIBLE (-3327 3350);
FORCEADD TAP..1
(-3325 3250);
FORCEPROP 3 LASTPIN (-3375 3250) SIG_NAME M_F_CPU1_SB_DQ<20>
J 0
(-3365 3260);
DISPLAY 0.659574 (-3365 3260);
PAINT MONO (-3365 3260);
DISPLAY INVISIBLE (-3365 3260);
FORCEPROP 1 LASTPIN (-3375 3250) BN 20
J 0
(-3387 3258);
DISPLAY 0.489362 (-3387 3258);
PAINT GREEN (-3387 3258);
FORCEPROP 2 LAST CDS_LIB mstr_standard
J 0
(-3325 3250);
DISPLAY 0.723404 (-3325 3250);
PAINT MONO (-3325 3250);
DISPLAY INVISIBLE (-3325 3250);
FORCEPROP 1 LAST BODY_TYPE PLUMBING
J 0
(-3325 3300);
DISPLAY 0.872340 (-3325 3300);
PAINT GREEN (-3325 3300);
DISPLAY INVISIBLE (-3325 3300);
FORCEPROP 1 LAST HDL_TAP TRUE
J 0
(-3000 3125);
DISPLAY 0.872340 (-3000 3125);
DISPLAY INVISIBLE (-3000 3125);
FORCEPROP 1 LAST PATH I215
J 0
(-3327 3250);
DISPLAY 0.872340 (-3327 3250);
PAINT GREEN (-3327 3250);
DISPLAY INVISIBLE (-3327 3250);
FORCEADD TAP..1
(-3325 3300);
FORCEPROP 3 LASTPIN (-3375 3300) SIG_NAME M_F_CPU1_SB_DQ<19>
J 0
(-3365 3310);
DISPLAY 0.659574 (-3365 3310);
PAINT MONO (-3365 3310);
DISPLAY INVISIBLE (-3365 3310);
FORCEPROP 1 LASTPIN (-3375 3300) BN 19
J 0
(-3387 3308);
DISPLAY 0.489362 (-3387 3308);
PAINT GREEN (-3387 3308);
FORCEPROP 2 LAST CDS_LIB mstr_standard
J 0
(-3325 3300);
DISPLAY 0.723404 (-3325 3300);
PAINT MONO (-3325 3300);
DISPLAY INVISIBLE (-3325 3300);
FORCEPROP 1 LAST BODY_TYPE PLUMBING
J 0
(-3325 3350);
DISPLAY 0.872340 (-3325 3350);
PAINT GREEN (-3325 3350);
DISPLAY INVISIBLE (-3325 3350);
FORCEPROP 1 LAST HDL_TAP TRUE
J 0
(-3000 3175);
DISPLAY 0.872340 (-3000 3175);
DISPLAY INVISIBLE (-3000 3175);
FORCEPROP 1 LAST PATH I216
J 0
(-3327 3300);
DISPLAY 0.872340 (-3327 3300);
PAINT GREEN (-3327 3300);
DISPLAY INVISIBLE (-3327 3300);
FORCEADD TAP..1
(-3325 3200);
FORCEPROP 3 LASTPIN (-3375 3200) SIG_NAME M_F_CPU1_SB_DQ<21>
J 0
(-3365 3210);
DISPLAY 0.659574 (-3365 3210);
PAINT MONO (-3365 3210);
DISPLAY INVISIBLE (-3365 3210);
FORCEPROP 1 LASTPIN (-3375 3200) BN 21
J 0
(-3387 3208);
DISPLAY 0.489362 (-3387 3208);
PAINT GREEN (-3387 3208);
FORCEPROP 2 LAST CDS_LIB mstr_standard
J 0
(-3325 3200);
DISPLAY 0.723404 (-3325 3200);
PAINT MONO (-3325 3200);
DISPLAY INVISIBLE (-3325 3200);
FORCEPROP 1 LAST BODY_TYPE PLUMBING
J 0
(-3325 3250);
DISPLAY 0.872340 (-3325 3250);
PAINT GREEN (-3325 3250);
DISPLAY INVISIBLE (-3325 3250);
FORCEPROP 1 LAST HDL_TAP TRUE
J 0
(-3000 3075);
DISPLAY 0.872340 (-3000 3075);
DISPLAY INVISIBLE (-3000 3075);
FORCEPROP 1 LAST PATH I217
J 0
(-3327 3200);
DISPLAY 0.872340 (-3327 3200);
PAINT GREEN (-3327 3200);
DISPLAY INVISIBLE (-3327 3200);
FORCEADD TAP..1
(-3325 3100);
FORCEPROP 3 LASTPIN (-3375 3100) SIG_NAME M_F_CPU1_SB_DQ<23>
J 0
(-3365 3110);
DISPLAY 0.659574 (-3365 3110);
PAINT MONO (-3365 3110);
DISPLAY INVISIBLE (-3365 3110);
FORCEPROP 1 LASTPIN (-3375 3100) BN 23
J 0
(-3387 3108);
DISPLAY 0.489362 (-3387 3108);
PAINT GREEN (-3387 3108);
FORCEPROP 2 LAST CDS_LIB mstr_standard
J 0
(-3325 3100);
DISPLAY 0.723404 (-3325 3100);
PAINT MONO (-3325 3100);
DISPLAY INVISIBLE (-3325 3100);
FORCEPROP 1 LAST BODY_TYPE PLUMBING
J 0
(-3325 3150);
DISPLAY 0.872340 (-3325 3150);
PAINT GREEN (-3325 3150);
DISPLAY INVISIBLE (-3325 3150);
FORCEPROP 1 LAST HDL_TAP TRUE
J 0
(-3000 2975);
DISPLAY 0.872340 (-3000 2975);
DISPLAY INVISIBLE (-3000 2975);
FORCEPROP 1 LAST PATH I218
J 0
(-3327 3100);
DISPLAY 0.872340 (-3327 3100);
PAINT GREEN (-3327 3100);
DISPLAY INVISIBLE (-3327 3100);
FORCEADD TAP..1
(-3325 3150);
FORCEPROP 3 LASTPIN (-3375 3150) SIG_NAME M_F_CPU1_SB_DQ<22>
J 0
(-3365 3160);
DISPLAY 0.659574 (-3365 3160);
PAINT MONO (-3365 3160);
DISPLAY INVISIBLE (-3365 3160);
FORCEPROP 1 LASTPIN (-3375 3150) BN 22
J 0
(-3387 3158);
DISPLAY 0.489362 (-3387 3158);
PAINT GREEN (-3387 3158);
FORCEPROP 2 LAST CDS_LIB mstr_standard
J 0
(-3325 3150);
DISPLAY 0.723404 (-3325 3150);
PAINT MONO (-3325 3150);
DISPLAY INVISIBLE (-3325 3150);
FORCEPROP 1 LAST BODY_TYPE PLUMBING
J 0
(-3325 3200);
DISPLAY 0.872340 (-3325 3200);
PAINT GREEN (-3325 3200);
DISPLAY INVISIBLE (-3325 3200);
FORCEPROP 1 LAST HDL_TAP TRUE
J 0
(-3000 3025);
DISPLAY 0.872340 (-3000 3025);
DISPLAY INVISIBLE (-3000 3025);
FORCEPROP 1 LAST PATH I219
J 0
(-3327 3150);
DISPLAY 0.872340 (-3327 3150);
PAINT GREEN (-3327 3150);
DISPLAY INVISIBLE (-3327 3150);
FORCEADD TAP..1
(-3325 3000);
FORCEPROP 3 LASTPIN (-3375 3000) SIG_NAME M_F_CPU1_SB_DQ<24>
J 0
(-3365 3010);
DISPLAY 0.659574 (-3365 3010);
PAINT MONO (-3365 3010);
DISPLAY INVISIBLE (-3365 3010);
FORCEPROP 1 LASTPIN (-3375 3000) BN 24
J 0
(-3387 3008);
DISPLAY 0.489362 (-3387 3008);
PAINT GREEN (-3387 3008);
FORCEPROP 2 LAST CDS_LIB mstr_standard
J 0
(-3325 3000);
DISPLAY 0.723404 (-3325 3000);
PAINT MONO (-3325 3000);
DISPLAY INVISIBLE (-3325 3000);
FORCEPROP 1 LAST BODY_TYPE PLUMBING
J 0
(-3325 3050);
DISPLAY 0.872340 (-3325 3050);
PAINT GREEN (-3325 3050);
DISPLAY INVISIBLE (-3325 3050);
FORCEPROP 1 LAST HDL_TAP TRUE
J 0
(-3000 2875);
DISPLAY 0.872340 (-3000 2875);
DISPLAY INVISIBLE (-3000 2875);
FORCEPROP 1 LAST PATH I220
J 0
(-3327 3000);
DISPLAY 0.872340 (-3327 3000);
PAINT GREEN (-3327 3000);
DISPLAY INVISIBLE (-3327 3000);
FORCEADD TAP..1
(-3325 2950);
FORCEPROP 3 LASTPIN (-3375 2950) SIG_NAME M_F_CPU1_SB_DQ<25>
J 0
(-3365 2960);
DISPLAY 0.659574 (-3365 2960);
PAINT MONO (-3365 2960);
DISPLAY INVISIBLE (-3365 2960);
FORCEPROP 1 LASTPIN (-3375 2950) BN 25
J 0
(-3387 2958);
DISPLAY 0.489362 (-3387 2958);
PAINT GREEN (-3387 2958);
FORCEPROP 2 LAST CDS_LIB mstr_standard
J 0
(-3325 2950);
DISPLAY 0.723404 (-3325 2950);
PAINT MONO (-3325 2950);
DISPLAY INVISIBLE (-3325 2950);
FORCEPROP 1 LAST BODY_TYPE PLUMBING
J 0
(-3325 3000);
DISPLAY 0.872340 (-3325 3000);
PAINT GREEN (-3325 3000);
DISPLAY INVISIBLE (-3325 3000);
FORCEPROP 1 LAST HDL_TAP TRUE
J 0
(-3000 2825);
DISPLAY 0.872340 (-3000 2825);
DISPLAY INVISIBLE (-3000 2825);
FORCEPROP 1 LAST PATH I221
J 0
(-3327 2950);
DISPLAY 0.872340 (-3327 2950);
PAINT GREEN (-3327 2950);
DISPLAY INVISIBLE (-3327 2950);
FORCEADD TAP..1
(-3325 2850);
FORCEPROP 3 LASTPIN (-3375 2850) SIG_NAME M_F_CPU1_SB_DQ<27>
J 0
(-3365 2860);
DISPLAY 0.659574 (-3365 2860);
PAINT MONO (-3365 2860);
DISPLAY INVISIBLE (-3365 2860);
FORCEPROP 1 LASTPIN (-3375 2850) BN 27
J 0
(-3387 2858);
DISPLAY 0.489362 (-3387 2858);
PAINT GREEN (-3387 2858);
FORCEPROP 2 LAST CDS_LIB mstr_standard
J 0
(-3325 2850);
DISPLAY 0.723404 (-3325 2850);
PAINT MONO (-3325 2850);
DISPLAY INVISIBLE (-3325 2850);
FORCEPROP 1 LAST BODY_TYPE PLUMBING
J 0
(-3325 2900);
DISPLAY 0.872340 (-3325 2900);
PAINT GREEN (-3325 2900);
DISPLAY INVISIBLE (-3325 2900);
FORCEPROP 1 LAST HDL_TAP TRUE
J 0
(-3000 2725);
DISPLAY 0.872340 (-3000 2725);
DISPLAY INVISIBLE (-3000 2725);
FORCEPROP 1 LAST PATH I222
J 0
(-3327 2850);
DISPLAY 0.872340 (-3327 2850);
PAINT GREEN (-3327 2850);
DISPLAY INVISIBLE (-3327 2850);
FORCEADD TAP..1
(-3325 2900);
FORCEPROP 3 LASTPIN (-3375 2900) SIG_NAME M_F_CPU1_SB_DQ<26>
J 0
(-3365 2910);
DISPLAY 0.659574 (-3365 2910);
PAINT MONO (-3365 2910);
DISPLAY INVISIBLE (-3365 2910);
FORCEPROP 1 LASTPIN (-3375 2900) BN 26
J 0
(-3387 2908);
DISPLAY 0.489362 (-3387 2908);
PAINT GREEN (-3387 2908);
FORCEPROP 2 LAST CDS_LIB mstr_standard
J 0
(-3325 2900);
DISPLAY 0.723404 (-3325 2900);
PAINT MONO (-3325 2900);
DISPLAY INVISIBLE (-3325 2900);
FORCEPROP 1 LAST BODY_TYPE PLUMBING
J 0
(-3325 2950);
DISPLAY 0.872340 (-3325 2950);
PAINT GREEN (-3325 2950);
DISPLAY INVISIBLE (-3325 2950);
FORCEPROP 1 LAST HDL_TAP TRUE
J 0
(-3000 2775);
DISPLAY 0.872340 (-3000 2775);
DISPLAY INVISIBLE (-3000 2775);
FORCEPROP 1 LAST PATH I223
J 0
(-3327 2900);
DISPLAY 0.872340 (-3327 2900);
PAINT GREEN (-3327 2900);
DISPLAY INVISIBLE (-3327 2900);
FORCEADD TAP..1
(-3325 2750);
FORCEPROP 3 LASTPIN (-3375 2750) SIG_NAME M_F_CPU1_SB_DQ<29>
J 0
(-3365 2760);
DISPLAY 0.659574 (-3365 2760);
PAINT MONO (-3365 2760);
DISPLAY INVISIBLE (-3365 2760);
FORCEPROP 1 LASTPIN (-3375 2750) BN 29
J 0
(-3387 2758);
DISPLAY 0.489362 (-3387 2758);
PAINT GREEN (-3387 2758);
FORCEPROP 2 LAST CDS_LIB mstr_standard
J 0
(-3325 2750);
DISPLAY 0.723404 (-3325 2750);
PAINT MONO (-3325 2750);
DISPLAY INVISIBLE (-3325 2750);
FORCEPROP 1 LAST BODY_TYPE PLUMBING
J 0
(-3325 2800);
DISPLAY 0.872340 (-3325 2800);
PAINT GREEN (-3325 2800);
DISPLAY INVISIBLE (-3325 2800);
FORCEPROP 1 LAST HDL_TAP TRUE
J 0
(-3000 2625);
DISPLAY 0.872340 (-3000 2625);
DISPLAY INVISIBLE (-3000 2625);
FORCEPROP 1 LAST PATH I224
J 0
(-3327 2750);
DISPLAY 0.872340 (-3327 2750);
PAINT GREEN (-3327 2750);
DISPLAY INVISIBLE (-3327 2750);
FORCEADD TAP..1
(-3325 2800);
FORCEPROP 3 LASTPIN (-3375 2800) SIG_NAME M_F_CPU1_SB_DQ<28>
J 0
(-3365 2810);
DISPLAY 0.659574 (-3365 2810);
PAINT MONO (-3365 2810);
DISPLAY INVISIBLE (-3365 2810);
FORCEPROP 1 LASTPIN (-3375 2800) BN 28
J 0
(-3387 2808);
DISPLAY 0.489362 (-3387 2808);
PAINT GREEN (-3387 2808);
FORCEPROP 2 LAST CDS_LIB mstr_standard
J 0
(-3325 2800);
DISPLAY 0.723404 (-3325 2800);
PAINT MONO (-3325 2800);
DISPLAY INVISIBLE (-3325 2800);
FORCEPROP 1 LAST BODY_TYPE PLUMBING
J 0
(-3325 2850);
DISPLAY 0.872340 (-3325 2850);
PAINT GREEN (-3325 2850);
DISPLAY INVISIBLE (-3325 2850);
FORCEPROP 1 LAST HDL_TAP TRUE
J 0
(-3000 2675);
DISPLAY 0.872340 (-3000 2675);
DISPLAY INVISIBLE (-3000 2675);
FORCEPROP 1 LAST PATH I225
J 0
(-3327 2800);
DISPLAY 0.872340 (-3327 2800);
PAINT GREEN (-3327 2800);
DISPLAY INVISIBLE (-3327 2800);
FORCEADD TAP..1
(-3325 2700);
FORCEPROP 3 LASTPIN (-3375 2700) SIG_NAME M_F_CPU1_SB_DQ<30>
J 0
(-3365 2710);
DISPLAY 0.659574 (-3365 2710);
PAINT MONO (-3365 2710);
DISPLAY INVISIBLE (-3365 2710);
FORCEPROP 1 LASTPIN (-3375 2700) BN 30
J 0
(-3387 2708);
DISPLAY 0.489362 (-3387 2708);
PAINT GREEN (-3387 2708);
FORCEPROP 2 LAST CDS_LIB mstr_standard
J 0
(-3325 2700);
DISPLAY 0.723404 (-3325 2700);
PAINT MONO (-3325 2700);
DISPLAY INVISIBLE (-3325 2700);
FORCEPROP 1 LAST BODY_TYPE PLUMBING
J 0
(-3325 2750);
DISPLAY 0.872340 (-3325 2750);
PAINT GREEN (-3325 2750);
DISPLAY INVISIBLE (-3325 2750);
FORCEPROP 1 LAST HDL_TAP TRUE
J 0
(-3000 2575);
DISPLAY 0.872340 (-3000 2575);
DISPLAY INVISIBLE (-3000 2575);
FORCEPROP 1 LAST PATH I226
J 0
(-3327 2700);
DISPLAY 0.872340 (-3327 2700);
PAINT GREEN (-3327 2700);
DISPLAY INVISIBLE (-3327 2700);
FORCEADD TAP..1
(-3325 2650);
FORCEPROP 3 LASTPIN (-3375 2650) SIG_NAME M_F_CPU1_SB_DQ<31>
J 0
(-3365 2660);
DISPLAY 0.659574 (-3365 2660);
PAINT MONO (-3365 2660);
DISPLAY INVISIBLE (-3365 2660);
FORCEPROP 1 LASTPIN (-3375 2650) BN 31
J 0
(-3387 2658);
DISPLAY 0.489362 (-3387 2658);
PAINT GREEN (-3387 2658);
FORCEPROP 2 LAST CDS_LIB mstr_standard
J 0
(-3325 2650);
DISPLAY 0.723404 (-3325 2650);
PAINT MONO (-3325 2650);
DISPLAY INVISIBLE (-3325 2650);
FORCEPROP 1 LAST BODY_TYPE PLUMBING
J 0
(-3325 2700);
DISPLAY 0.872340 (-3325 2700);
PAINT GREEN (-3325 2700);
DISPLAY INVISIBLE (-3325 2700);
FORCEPROP 1 LAST HDL_TAP TRUE
J 0
(-3000 2525);
DISPLAY 0.872340 (-3000 2525);
DISPLAY INVISIBLE (-3000 2525);
FORCEPROP 1 LAST PATH I227
J 0
(-3327 2650);
DISPLAY 0.872340 (-3327 2650);
PAINT GREEN (-3327 2650);
DISPLAY INVISIBLE (-3327 2650);
FORCEADD TAP..1
(-3325 2500);
FORCEPROP 3 LASTPIN (-3375 2500) SIG_NAME M_F_CPU1_SA_CB<1>
J 0
(-3365 2510);
DISPLAY 0.659574 (-3365 2510);
PAINT MONO (-3365 2510);
DISPLAY INVISIBLE (-3365 2510);
FORCEPROP 1 LASTPIN (-3375 2500) BN 1
J 0
(-3387 2508);
DISPLAY 0.489362 (-3387 2508);
PAINT GREEN (-3387 2508);
FORCEPROP 2 LAST CDS_LIB mstr_standard
J 2
(-3325 2500);
DISPLAY 0.723404 (-3325 2500);
PAINT MONO (-3325 2500);
DISPLAY INVISIBLE (-3325 2500);
FORCEPROP 1 LAST BODY_TYPE PLUMBING
J 0
(-3325 2550);
DISPLAY 0.872340 (-3325 2550);
PAINT GREEN (-3325 2550);
DISPLAY INVISIBLE (-3325 2550);
FORCEPROP 1 LAST HDL_TAP TRUE
J 0
(-3000 2375);
DISPLAY 0.872340 (-3000 2375);
DISPLAY INVISIBLE (-3000 2375);
FORCEPROP 1 LAST PATH I228
J 0
(-3327 2500);
DISPLAY 0.872340 (-3327 2500);
PAINT GREEN (-3327 2500);
DISPLAY INVISIBLE (-3327 2500);
FORCEADD TAP..1
(-3325 2450);
FORCEPROP 3 LASTPIN (-3375 2450) SIG_NAME M_F_CPU1_SA_CB<2>
J 0
(-3365 2460);
DISPLAY 0.659574 (-3365 2460);
PAINT MONO (-3365 2460);
DISPLAY INVISIBLE (-3365 2460);
FORCEPROP 1 LASTPIN (-3375 2450) BN 2
J 0
(-3387 2458);
DISPLAY 0.489362 (-3387 2458);
PAINT GREEN (-3387 2458);
FORCEPROP 2 LAST CDS_LIB mstr_standard
J 2
(-3325 2450);
DISPLAY 0.723404 (-3325 2450);
PAINT MONO (-3325 2450);
DISPLAY INVISIBLE (-3325 2450);
FORCEPROP 1 LAST BODY_TYPE PLUMBING
J 0
(-3325 2500);
DISPLAY 0.872340 (-3325 2500);
PAINT GREEN (-3325 2500);
DISPLAY INVISIBLE (-3325 2500);
FORCEPROP 1 LAST HDL_TAP TRUE
J 0
(-3000 2325);
DISPLAY 0.872340 (-3000 2325);
DISPLAY INVISIBLE (-3000 2325);
FORCEPROP 1 LAST PATH I229
J 0
(-3327 2450);
DISPLAY 0.872340 (-3327 2450);
PAINT GREEN (-3327 2450);
DISPLAY INVISIBLE (-3327 2450);
FORCEADD TAP..1
(-3325 2550);
FORCEPROP 3 LASTPIN (-3375 2550) SIG_NAME M_F_CPU1_SA_CB<0>
J 0
(-3365 2560);
DISPLAY 0.659574 (-3365 2560);
PAINT MONO (-3365 2560);
DISPLAY INVISIBLE (-3365 2560);
FORCEPROP 1 LASTPIN (-3375 2550) BN 0
J 0
(-3387 2558);
DISPLAY 0.489362 (-3387 2558);
PAINT GREEN (-3387 2558);
FORCEPROP 2 LAST CDS_LIB mstr_standard
J 2
(-3325 2550);
DISPLAY 0.723404 (-3325 2550);
PAINT MONO (-3325 2550);
DISPLAY INVISIBLE (-3325 2550);
FORCEPROP 1 LAST BODY_TYPE PLUMBING
J 0
(-3325 2600);
DISPLAY 0.872340 (-3325 2600);
PAINT GREEN (-3325 2600);
DISPLAY INVISIBLE (-3325 2600);
FORCEPROP 1 LAST HDL_TAP TRUE
J 0
(-3000 2425);
DISPLAY 0.872340 (-3000 2425);
DISPLAY INVISIBLE (-3000 2425);
FORCEPROP 1 LAST PATH I230
J 0
(-3327 2550);
DISPLAY 0.872340 (-3327 2550);
PAINT GREEN (-3327 2550);
DISPLAY INVISIBLE (-3327 2550);
FORCEADD TAP..1
(-3325 2400);
FORCEPROP 3 LASTPIN (-3375 2400) SIG_NAME M_F_CPU1_SA_CB<3>
J 0
(-3365 2410);
DISPLAY 0.659574 (-3365 2410);
PAINT MONO (-3365 2410);
DISPLAY INVISIBLE (-3365 2410);
FORCEPROP 1 LASTPIN (-3375 2400) BN 3
J 0
(-3387 2408);
DISPLAY 0.489362 (-3387 2408);
PAINT GREEN (-3387 2408);
FORCEPROP 2 LAST CDS_LIB mstr_standard
J 2
(-3325 2400);
DISPLAY 0.723404 (-3325 2400);
PAINT MONO (-3325 2400);
DISPLAY INVISIBLE (-3325 2400);
FORCEPROP 1 LAST BODY_TYPE PLUMBING
J 0
(-3325 2450);
DISPLAY 0.872340 (-3325 2450);
PAINT GREEN (-3325 2450);
DISPLAY INVISIBLE (-3325 2450);
FORCEPROP 1 LAST HDL_TAP TRUE
J 0
(-3000 2275);
DISPLAY 0.872340 (-3000 2275);
DISPLAY INVISIBLE (-3000 2275);
FORCEPROP 1 LAST PATH I231
J 0
(-3327 2400);
DISPLAY 0.872340 (-3327 2400);
PAINT GREEN (-3327 2400);
DISPLAY INVISIBLE (-3327 2400);
FORCEADD TAP..1
(-3325 2350);
FORCEPROP 3 LASTPIN (-3375 2350) SIG_NAME M_F_CPU1_SA_CB<4>
J 0
(-3365 2360);
DISPLAY 0.659574 (-3365 2360);
PAINT MONO (-3365 2360);
DISPLAY INVISIBLE (-3365 2360);
FORCEPROP 1 LASTPIN (-3375 2350) BN 4
J 0
(-3387 2358);
DISPLAY 0.489362 (-3387 2358);
PAINT GREEN (-3387 2358);
FORCEPROP 2 LAST CDS_LIB mstr_standard
J 2
(-3325 2350);
DISPLAY 0.723404 (-3325 2350);
PAINT MONO (-3325 2350);
DISPLAY INVISIBLE (-3325 2350);
FORCEPROP 1 LAST BODY_TYPE PLUMBING
J 0
(-3325 2400);
DISPLAY 0.872340 (-3325 2400);
PAINT GREEN (-3325 2400);
DISPLAY INVISIBLE (-3325 2400);
FORCEPROP 1 LAST HDL_TAP TRUE
J 0
(-3000 2225);
DISPLAY 0.872340 (-3000 2225);
DISPLAY INVISIBLE (-3000 2225);
FORCEPROP 1 LAST PATH I232
J 0
(-3327 2350);
DISPLAY 0.872340 (-3327 2350);
PAINT GREEN (-3327 2350);
DISPLAY INVISIBLE (-3327 2350);
FORCEADD TAP..1
(-3325 2200);
FORCEPROP 3 LASTPIN (-3375 2200) SIG_NAME M_F_CPU1_SA_CB<7>
J 0
(-3365 2210);
DISPLAY 0.659574 (-3365 2210);
PAINT MONO (-3365 2210);
DISPLAY INVISIBLE (-3365 2210);
FORCEPROP 1 LASTPIN (-3375 2200) BN 7
J 0
(-3387 2208);
DISPLAY 0.489362 (-3387 2208);
PAINT GREEN (-3387 2208);
FORCEPROP 2 LAST CDS_LIB mstr_standard
J 2
(-3325 2200);
DISPLAY 0.723404 (-3325 2200);
PAINT MONO (-3325 2200);
DISPLAY INVISIBLE (-3325 2200);
FORCEPROP 1 LAST BODY_TYPE PLUMBING
J 0
(-3325 2250);
DISPLAY 0.872340 (-3325 2250);
PAINT GREEN (-3325 2250);
DISPLAY INVISIBLE (-3325 2250);
FORCEPROP 1 LAST HDL_TAP TRUE
J 0
(-3000 2075);
DISPLAY 0.872340 (-3000 2075);
DISPLAY INVISIBLE (-3000 2075);
FORCEPROP 1 LAST PATH I233
J 0
(-3327 2200);
DISPLAY 0.872340 (-3327 2200);
PAINT GREEN (-3327 2200);
DISPLAY INVISIBLE (-3327 2200);
FORCEADD TAP..1
(-3325 2300);
FORCEPROP 3 LASTPIN (-3375 2300) SIG_NAME M_F_CPU1_SA_CB<5>
J 0
(-3365 2310);
DISPLAY 0.659574 (-3365 2310);
PAINT MONO (-3365 2310);
DISPLAY INVISIBLE (-3365 2310);
FORCEPROP 1 LASTPIN (-3375 2300) BN 5
J 0
(-3387 2308);
DISPLAY 0.489362 (-3387 2308);
PAINT GREEN (-3387 2308);
FORCEPROP 2 LAST CDS_LIB mstr_standard
J 2
(-3325 2300);
DISPLAY 0.723404 (-3325 2300);
PAINT MONO (-3325 2300);
DISPLAY INVISIBLE (-3325 2300);
FORCEPROP 1 LAST BODY_TYPE PLUMBING
J 0
(-3325 2350);
DISPLAY 0.872340 (-3325 2350);
PAINT GREEN (-3325 2350);
DISPLAY INVISIBLE (-3325 2350);
FORCEPROP 1 LAST HDL_TAP TRUE
J 0
(-3000 2175);
DISPLAY 0.872340 (-3000 2175);
DISPLAY INVISIBLE (-3000 2175);
FORCEPROP 1 LAST PATH I234
J 0
(-3327 2300);
DISPLAY 0.872340 (-3327 2300);
PAINT GREEN (-3327 2300);
DISPLAY INVISIBLE (-3327 2300);
FORCEADD TAP..1
(-3325 2250);
FORCEPROP 3 LASTPIN (-3375 2250) SIG_NAME M_F_CPU1_SA_CB<6>
J 0
(-3365 2260);
DISPLAY 0.659574 (-3365 2260);
PAINT MONO (-3365 2260);
DISPLAY INVISIBLE (-3365 2260);
FORCEPROP 1 LASTPIN (-3375 2250) BN 6
J 0
(-3387 2258);
DISPLAY 0.489362 (-3387 2258);
PAINT GREEN (-3387 2258);
FORCEPROP 2 LAST CDS_LIB mstr_standard
J 2
(-3325 2250);
DISPLAY 0.723404 (-3325 2250);
PAINT MONO (-3325 2250);
DISPLAY INVISIBLE (-3325 2250);
FORCEPROP 1 LAST BODY_TYPE PLUMBING
J 0
(-3325 2300);
DISPLAY 0.872340 (-3325 2300);
PAINT GREEN (-3325 2300);
DISPLAY INVISIBLE (-3325 2300);
FORCEPROP 1 LAST HDL_TAP TRUE
J 0
(-3000 2125);
DISPLAY 0.872340 (-3000 2125);
DISPLAY INVISIBLE (-3000 2125);
FORCEPROP 1 LAST PATH I235
J 0
(-3327 2250);
DISPLAY 0.872340 (-3327 2250);
PAINT GREEN (-3327 2250);
DISPLAY INVISIBLE (-3327 2250);
FORCEADD TAP..1
(-3325 2050);
FORCEPROP 3 LASTPIN (-3375 2050) SIG_NAME M_F_CPU1_SB_CB<1>
J 0
(-3365 2060);
DISPLAY 0.659574 (-3365 2060);
PAINT MONO (-3365 2060);
DISPLAY INVISIBLE (-3365 2060);
FORCEPROP 1 LASTPIN (-3375 2050) BN 1
J 0
(-3387 2058);
DISPLAY 0.489362 (-3387 2058);
PAINT GREEN (-3387 2058);
FORCEPROP 2 LAST CDS_LIB mstr_standard
J 2
(-3325 2050);
DISPLAY 0.723404 (-3325 2050);
PAINT MONO (-3325 2050);
DISPLAY INVISIBLE (-3325 2050);
FORCEPROP 1 LAST BODY_TYPE PLUMBING
J 0
(-3325 2100);
DISPLAY 0.872340 (-3325 2100);
PAINT GREEN (-3325 2100);
DISPLAY INVISIBLE (-3325 2100);
FORCEPROP 1 LAST HDL_TAP TRUE
J 0
(-3000 1925);
DISPLAY 0.872340 (-3000 1925);
DISPLAY INVISIBLE (-3000 1925);
FORCEPROP 1 LAST PATH I236
J 0
(-3327 2050);
DISPLAY 0.872340 (-3327 2050);
PAINT GREEN (-3327 2050);
DISPLAY INVISIBLE (-3327 2050);
FORCEADD TAP..1
(-3325 2100);
FORCEPROP 3 LASTPIN (-3375 2100) SIG_NAME M_F_CPU1_SB_CB<0>
J 0
(-3365 2110);
DISPLAY 0.659574 (-3365 2110);
PAINT MONO (-3365 2110);
DISPLAY INVISIBLE (-3365 2110);
FORCEPROP 1 LASTPIN (-3375 2100) BN 0
J 0
(-3387 2108);
DISPLAY 0.489362 (-3387 2108);
PAINT GREEN (-3387 2108);
FORCEPROP 2 LAST CDS_LIB mstr_standard
J 2
(-3325 2100);
DISPLAY 0.723404 (-3325 2100);
PAINT MONO (-3325 2100);
DISPLAY INVISIBLE (-3325 2100);
FORCEPROP 1 LAST BODY_TYPE PLUMBING
J 0
(-3325 2150);
DISPLAY 0.872340 (-3325 2150);
PAINT GREEN (-3325 2150);
DISPLAY INVISIBLE (-3325 2150);
FORCEPROP 1 LAST HDL_TAP TRUE
J 0
(-3000 1975);
DISPLAY 0.872340 (-3000 1975);
DISPLAY INVISIBLE (-3000 1975);
FORCEPROP 1 LAST PATH I237
J 0
(-3327 2100);
DISPLAY 0.872340 (-3327 2100);
PAINT GREEN (-3327 2100);
DISPLAY INVISIBLE (-3327 2100);
FORCEADD TAP..1
(-3325 2000);
FORCEPROP 3 LASTPIN (-3375 2000) SIG_NAME M_F_CPU1_SB_CB<2>
J 0
(-3365 2010);
DISPLAY 0.659574 (-3365 2010);
PAINT MONO (-3365 2010);
DISPLAY INVISIBLE (-3365 2010);
FORCEPROP 1 LASTPIN (-3375 2000) BN 2
J 0
(-3387 2008);
DISPLAY 0.489362 (-3387 2008);
PAINT GREEN (-3387 2008);
FORCEPROP 2 LAST CDS_LIB mstr_standard
J 2
(-3325 2000);
DISPLAY 0.723404 (-3325 2000);
PAINT MONO (-3325 2000);
DISPLAY INVISIBLE (-3325 2000);
FORCEPROP 1 LAST BODY_TYPE PLUMBING
J 0
(-3325 2050);
DISPLAY 0.872340 (-3325 2050);
PAINT GREEN (-3325 2050);
DISPLAY INVISIBLE (-3325 2050);
FORCEPROP 1 LAST HDL_TAP TRUE
J 0
(-3000 1875);
DISPLAY 0.872340 (-3000 1875);
DISPLAY INVISIBLE (-3000 1875);
FORCEPROP 1 LAST PATH I238
J 0
(-3327 2000);
DISPLAY 0.872340 (-3327 2000);
PAINT GREEN (-3327 2000);
DISPLAY INVISIBLE (-3327 2000);
FORCEADD TAP..1
(-3325 1950);
FORCEPROP 3 LASTPIN (-3375 1950) SIG_NAME M_F_CPU1_SB_CB<3>
J 0
(-3365 1960);
DISPLAY 0.659574 (-3365 1960);
PAINT MONO (-3365 1960);
DISPLAY INVISIBLE (-3365 1960);
FORCEPROP 1 LASTPIN (-3375 1950) BN 3
J 0
(-3387 1958);
DISPLAY 0.489362 (-3387 1958);
PAINT GREEN (-3387 1958);
FORCEPROP 2 LAST CDS_LIB mstr_standard
J 2
(-3325 1950);
DISPLAY 0.723404 (-3325 1950);
PAINT MONO (-3325 1950);
DISPLAY INVISIBLE (-3325 1950);
FORCEPROP 1 LAST BODY_TYPE PLUMBING
J 0
(-3325 2000);
DISPLAY 0.872340 (-3325 2000);
PAINT GREEN (-3325 2000);
DISPLAY INVISIBLE (-3325 2000);
FORCEPROP 1 LAST HDL_TAP TRUE
J 0
(-3000 1825);
DISPLAY 0.872340 (-3000 1825);
DISPLAY INVISIBLE (-3000 1825);
FORCEPROP 1 LAST PATH I239
J 0
(-3327 1950);
DISPLAY 0.872340 (-3327 1950);
PAINT GREEN (-3327 1950);
DISPLAY INVISIBLE (-3327 1950);
FORCEADD TAP..1
(-3325 1800);
FORCEPROP 3 LASTPIN (-3375 1800) SIG_NAME M_F_CPU1_SB_CB<6>
J 0
(-3365 1810);
DISPLAY 0.659574 (-3365 1810);
PAINT MONO (-3365 1810);
DISPLAY INVISIBLE (-3365 1810);
FORCEPROP 1 LASTPIN (-3375 1800) BN 6
J 0
(-3387 1808);
DISPLAY 0.489362 (-3387 1808);
PAINT GREEN (-3387 1808);
FORCEPROP 2 LAST CDS_LIB mstr_standard
J 2
(-3325 1800);
DISPLAY 0.723404 (-3325 1800);
PAINT MONO (-3325 1800);
DISPLAY INVISIBLE (-3325 1800);
FORCEPROP 1 LAST BODY_TYPE PLUMBING
J 0
(-3325 1850);
DISPLAY 0.872340 (-3325 1850);
PAINT GREEN (-3325 1850);
DISPLAY INVISIBLE (-3325 1850);
FORCEPROP 1 LAST HDL_TAP TRUE
J 0
(-3000 1675);
DISPLAY 0.872340 (-3000 1675);
DISPLAY INVISIBLE (-3000 1675);
FORCEPROP 1 LAST PATH I240
J 0
(-3327 1800);
DISPLAY 0.872340 (-3327 1800);
PAINT GREEN (-3327 1800);
DISPLAY INVISIBLE (-3327 1800);
FORCEADD TAP..1
(-3325 1900);
FORCEPROP 3 LASTPIN (-3375 1900) SIG_NAME M_F_CPU1_SB_CB<4>
J 0
(-3365 1910);
DISPLAY 0.659574 (-3365 1910);
PAINT MONO (-3365 1910);
DISPLAY INVISIBLE (-3365 1910);
FORCEPROP 1 LASTPIN (-3375 1900) BN 4
J 0
(-3387 1908);
DISPLAY 0.489362 (-3387 1908);
PAINT GREEN (-3387 1908);
FORCEPROP 2 LAST CDS_LIB mstr_standard
J 2
(-3325 1900);
DISPLAY 0.723404 (-3325 1900);
PAINT MONO (-3325 1900);
DISPLAY INVISIBLE (-3325 1900);
FORCEPROP 1 LAST BODY_TYPE PLUMBING
J 0
(-3325 1950);
DISPLAY 0.872340 (-3325 1950);
PAINT GREEN (-3325 1950);
DISPLAY INVISIBLE (-3325 1950);
FORCEPROP 1 LAST HDL_TAP TRUE
J 0
(-3000 1775);
DISPLAY 0.872340 (-3000 1775);
DISPLAY INVISIBLE (-3000 1775);
FORCEPROP 1 LAST PATH I241
J 0
(-3327 1900);
DISPLAY 0.872340 (-3327 1900);
PAINT GREEN (-3327 1900);
DISPLAY INVISIBLE (-3327 1900);
FORCEADD TAP..1
(-3325 1850);
FORCEPROP 3 LASTPIN (-3375 1850) SIG_NAME M_F_CPU1_SB_CB<5>
J 0
(-3365 1860);
DISPLAY 0.659574 (-3365 1860);
PAINT MONO (-3365 1860);
DISPLAY INVISIBLE (-3365 1860);
FORCEPROP 1 LASTPIN (-3375 1850) BN 5
J 0
(-3387 1858);
DISPLAY 0.489362 (-3387 1858);
PAINT GREEN (-3387 1858);
FORCEPROP 2 LAST CDS_LIB mstr_standard
J 2
(-3325 1850);
DISPLAY 0.723404 (-3325 1850);
PAINT MONO (-3325 1850);
DISPLAY INVISIBLE (-3325 1850);
FORCEPROP 1 LAST BODY_TYPE PLUMBING
J 0
(-3325 1900);
DISPLAY 0.872340 (-3325 1900);
PAINT GREEN (-3325 1900);
DISPLAY INVISIBLE (-3325 1900);
FORCEPROP 1 LAST HDL_TAP TRUE
J 0
(-3000 1725);
DISPLAY 0.872340 (-3000 1725);
DISPLAY INVISIBLE (-3000 1725);
FORCEPROP 1 LAST PATH I242
J 0
(-3327 1850);
DISPLAY 0.872340 (-3327 1850);
PAINT GREEN (-3327 1850);
DISPLAY INVISIBLE (-3327 1850);
FORCEADD TAP..1
(-3325 1750);
FORCEPROP 3 LASTPIN (-3375 1750) SIG_NAME M_F_CPU1_SB_CB<7>
J 0
(-3365 1760);
DISPLAY 0.659574 (-3365 1760);
PAINT MONO (-3365 1760);
DISPLAY INVISIBLE (-3365 1760);
FORCEPROP 1 LASTPIN (-3375 1750) BN 7
J 0
(-3387 1758);
DISPLAY 0.489362 (-3387 1758);
PAINT GREEN (-3387 1758);
FORCEPROP 2 LAST CDS_LIB mstr_standard
J 2
(-3325 1750);
DISPLAY 0.723404 (-3325 1750);
PAINT MONO (-3325 1750);
DISPLAY INVISIBLE (-3325 1750);
FORCEPROP 1 LAST BODY_TYPE PLUMBING
J 0
(-3325 1800);
DISPLAY 0.872340 (-3325 1800);
PAINT GREEN (-3325 1800);
DISPLAY INVISIBLE (-3325 1800);
FORCEPROP 1 LAST HDL_TAP TRUE
J 0
(-3000 1625);
DISPLAY 0.872340 (-3000 1625);
DISPLAY INVISIBLE (-3000 1625);
FORCEPROP 1 LAST PATH I243
J 0
(-3327 1750);
DISPLAY 0.872340 (-3327 1750);
PAINT GREEN (-3327 1750);
DISPLAY INVISIBLE (-3327 1750);
FORCEADD TAP..1
R 2
(-5750 6150);
FORCEPROP 3 LASTPIN (-5700 6150) SIG_NAME M_F_CPU1_SA_DQS_DP<0>
J 0
(-5690 6160);
DISPLAY 0.659574 (-5690 6160);
PAINT MONO (-5690 6160);
DISPLAY INVISIBLE (-5690 6160);
FORCEPROP 1 LASTPIN (-5700 6150) BN 0
J 2
(-5688 6158);
DISPLAY 0.489362 (-5688 6158);
PAINT GREEN (-5688 6158);
FORCEPROP 2 LAST CDS_LIB mstr_standard
J 2
(-5750 6150);
DISPLAY 0.723404 (-5750 6150);
PAINT MONO (-5750 6150);
DISPLAY INVISIBLE (-5750 6150);
FORCEPROP 1 LAST BODY_TYPE PLUMBING
J 2
(-5750 6200);
DISPLAY 0.872340 (-5750 6200);
PAINT GREEN (-5750 6200);
DISPLAY INVISIBLE (-5750 6200);
FORCEPROP 1 LAST HDL_TAP TRUE
J 2
(-6075 6025);
DISPLAY 0.872340 (-6075 6025);
DISPLAY INVISIBLE (-6075 6025);
FORCEPROP 1 LAST PATH I244
J 2
(-5748 6150);
DISPLAY 0.872340 (-5748 6150);
PAINT GREEN (-5748 6150);
DISPLAY INVISIBLE (-5748 6150);
FORCEADD TAP..1
R 2
(-5750 6050);
FORCEPROP 3 LASTPIN (-5700 6050) SIG_NAME M_F_CPU1_SA_DQS_DP<1>
J 0
(-5690 6060);
DISPLAY 0.659574 (-5690 6060);
PAINT MONO (-5690 6060);
DISPLAY INVISIBLE (-5690 6060);
FORCEPROP 1 LASTPIN (-5700 6050) BN 1
J 2
(-5688 6058);
DISPLAY 0.489362 (-5688 6058);
PAINT GREEN (-5688 6058);
FORCEPROP 2 LAST CDS_LIB mstr_standard
J 2
(-5750 6050);
DISPLAY 0.723404 (-5750 6050);
PAINT MONO (-5750 6050);
DISPLAY INVISIBLE (-5750 6050);
FORCEPROP 1 LAST BODY_TYPE PLUMBING
J 2
(-5750 6100);
DISPLAY 0.872340 (-5750 6100);
PAINT GREEN (-5750 6100);
DISPLAY INVISIBLE (-5750 6100);
FORCEPROP 1 LAST HDL_TAP TRUE
J 2
(-6075 5925);
DISPLAY 0.872340 (-6075 5925);
DISPLAY INVISIBLE (-6075 5925);
FORCEPROP 1 LAST PATH I245
J 2
(-5748 6050);
DISPLAY 0.872340 (-5748 6050);
PAINT GREEN (-5748 6050);
DISPLAY INVISIBLE (-5748 6050);
FORCEADD TAP..1
R 2
(-5750 5950);
FORCEPROP 3 LASTPIN (-5700 5950) SIG_NAME M_F_CPU1_SA_DQS_DP<2>
J 0
(-5690 5960);
DISPLAY 0.659574 (-5690 5960);
PAINT MONO (-5690 5960);
DISPLAY INVISIBLE (-5690 5960);
FORCEPROP 1 LASTPIN (-5700 5950) BN 2
J 2
(-5688 5958);
DISPLAY 0.489362 (-5688 5958);
PAINT GREEN (-5688 5958);
FORCEPROP 2 LAST CDS_LIB mstr_standard
J 2
(-5750 5950);
DISPLAY 0.723404 (-5750 5950);
PAINT MONO (-5750 5950);
DISPLAY INVISIBLE (-5750 5950);
FORCEPROP 1 LAST BODY_TYPE PLUMBING
J 2
(-5750 6000);
DISPLAY 0.872340 (-5750 6000);
PAINT GREEN (-5750 6000);
DISPLAY INVISIBLE (-5750 6000);
FORCEPROP 1 LAST HDL_TAP TRUE
J 2
(-6075 5825);
DISPLAY 0.872340 (-6075 5825);
DISPLAY INVISIBLE (-6075 5825);
FORCEPROP 1 LAST PATH I246
J 2
(-5748 5950);
DISPLAY 0.872340 (-5748 5950);
PAINT GREEN (-5748 5950);
DISPLAY INVISIBLE (-5748 5950);
FORCEADD TAP..1
R 2
(-5750 5850);
FORCEPROP 3 LASTPIN (-5700 5850) SIG_NAME M_F_CPU1_SA_DQS_DP<3>
J 0
(-5690 5860);
DISPLAY 0.659574 (-5690 5860);
PAINT MONO (-5690 5860);
DISPLAY INVISIBLE (-5690 5860);
FORCEPROP 1 LASTPIN (-5700 5850) BN 3
J 2
(-5688 5858);
DISPLAY 0.489362 (-5688 5858);
PAINT GREEN (-5688 5858);
FORCEPROP 2 LAST CDS_LIB mstr_standard
J 2
(-5750 5850);
DISPLAY 0.723404 (-5750 5850);
PAINT MONO (-5750 5850);
DISPLAY INVISIBLE (-5750 5850);
FORCEPROP 1 LAST BODY_TYPE PLUMBING
J 2
(-5750 5900);
DISPLAY 0.872340 (-5750 5900);
PAINT GREEN (-5750 5900);
DISPLAY INVISIBLE (-5750 5900);
FORCEPROP 1 LAST HDL_TAP TRUE
J 2
(-6075 5725);
DISPLAY 0.872340 (-6075 5725);
DISPLAY INVISIBLE (-6075 5725);
FORCEPROP 1 LAST PATH I247
J 2
(-5748 5850);
DISPLAY 0.872340 (-5748 5850);
PAINT GREEN (-5748 5850);
DISPLAY INVISIBLE (-5748 5850);
FORCEADD TAP..1
R 2
(-5750 5650);
FORCEPROP 3 LASTPIN (-5700 5650) SIG_NAME M_F_CPU1_SA_DQS_DP<5>
J 0
(-5690 5660);
DISPLAY 0.659574 (-5690 5660);
PAINT MONO (-5690 5660);
DISPLAY INVISIBLE (-5690 5660);
FORCEPROP 1 LASTPIN (-5700 5650) BN 5
J 2
(-5688 5658);
DISPLAY 0.489362 (-5688 5658);
PAINT GREEN (-5688 5658);
FORCEPROP 2 LAST CDS_LIB mstr_standard
J 2
(-5750 5650);
DISPLAY 0.723404 (-5750 5650);
PAINT MONO (-5750 5650);
DISPLAY INVISIBLE (-5750 5650);
FORCEPROP 1 LAST BODY_TYPE PLUMBING
J 2
(-5750 5700);
DISPLAY 0.872340 (-5750 5700);
PAINT GREEN (-5750 5700);
DISPLAY INVISIBLE (-5750 5700);
FORCEPROP 1 LAST HDL_TAP TRUE
J 2
(-6075 5525);
DISPLAY 0.872340 (-6075 5525);
DISPLAY INVISIBLE (-6075 5525);
FORCEPROP 1 LAST PATH I248
J 2
(-5748 5650);
DISPLAY 0.872340 (-5748 5650);
PAINT GREEN (-5748 5650);
DISPLAY INVISIBLE (-5748 5650);
FORCEADD TAP..1
R 2
(-5750 5750);
FORCEPROP 3 LASTPIN (-5700 5750) SIG_NAME M_F_CPU1_SA_DQS_DP<4>
J 0
(-5690 5760);
DISPLAY 0.659574 (-5690 5760);
PAINT MONO (-5690 5760);
DISPLAY INVISIBLE (-5690 5760);
FORCEPROP 1 LASTPIN (-5700 5750) BN 4
J 2
(-5688 5758);
DISPLAY 0.489362 (-5688 5758);
PAINT GREEN (-5688 5758);
FORCEPROP 2 LAST CDS_LIB mstr_standard
J 2
(-5750 5750);
DISPLAY 0.723404 (-5750 5750);
PAINT MONO (-5750 5750);
DISPLAY INVISIBLE (-5750 5750);
FORCEPROP 1 LAST BODY_TYPE PLUMBING
J 2
(-5750 5800);
DISPLAY 0.872340 (-5750 5800);
PAINT GREEN (-5750 5800);
DISPLAY INVISIBLE (-5750 5800);
FORCEPROP 1 LAST HDL_TAP TRUE
J 2
(-6075 5625);
DISPLAY 0.872340 (-6075 5625);
DISPLAY INVISIBLE (-6075 5625);
FORCEPROP 1 LAST PATH I249
J 2
(-5748 5750);
DISPLAY 0.872340 (-5748 5750);
PAINT GREEN (-5748 5750);
DISPLAY INVISIBLE (-5748 5750);
FORCEADD TAP..1
R 2
(-5950 6100);
FORCEPROP 3 LASTPIN (-5900 6100) SIG_NAME M_F_CPU1_SA_DQS_DN<0>
J 0
(-5890 6110);
DISPLAY 0.659574 (-5890 6110);
PAINT MONO (-5890 6110);
DISPLAY INVISIBLE (-5890 6110);
FORCEPROP 1 LASTPIN (-5900 6100) BN 0
J 2
(-5888 6108);
DISPLAY 0.489362 (-5888 6108);
PAINT GREEN (-5888 6108);
FORCEPROP 2 LAST CDS_LIB mstr_standard
J 2
(-5950 6100);
DISPLAY 0.723404 (-5950 6100);
PAINT MONO (-5950 6100);
DISPLAY INVISIBLE (-5950 6100);
FORCEPROP 1 LAST BODY_TYPE PLUMBING
J 2
(-5950 6150);
DISPLAY 0.872340 (-5950 6150);
PAINT GREEN (-5950 6150);
DISPLAY INVISIBLE (-5950 6150);
FORCEPROP 1 LAST HDL_TAP TRUE
J 2
(-6275 5975);
DISPLAY 0.872340 (-6275 5975);
DISPLAY INVISIBLE (-6275 5975);
FORCEPROP 1 LAST PATH I250
J 2
(-5948 6100);
DISPLAY 0.872340 (-5948 6100);
PAINT GREEN (-5948 6100);
DISPLAY INVISIBLE (-5948 6100);
FORCEADD TAP..1
R 2
(-5950 6000);
FORCEPROP 3 LASTPIN (-5900 6000) SIG_NAME M_F_CPU1_SA_DQS_DN<1>
J 0
(-5890 6010);
DISPLAY 0.659574 (-5890 6010);
PAINT MONO (-5890 6010);
DISPLAY INVISIBLE (-5890 6010);
FORCEPROP 1 LASTPIN (-5900 6000) BN 1
J 2
(-5888 6008);
DISPLAY 0.489362 (-5888 6008);
PAINT GREEN (-5888 6008);
FORCEPROP 2 LAST CDS_LIB mstr_standard
J 2
(-5950 6000);
DISPLAY 0.723404 (-5950 6000);
PAINT MONO (-5950 6000);
DISPLAY INVISIBLE (-5950 6000);
FORCEPROP 1 LAST BODY_TYPE PLUMBING
J 2
(-5950 6050);
DISPLAY 0.872340 (-5950 6050);
PAINT GREEN (-5950 6050);
DISPLAY INVISIBLE (-5950 6050);
FORCEPROP 1 LAST HDL_TAP TRUE
J 2
(-6275 5875);
DISPLAY 0.872340 (-6275 5875);
DISPLAY INVISIBLE (-6275 5875);
FORCEPROP 1 LAST PATH I251
J 2
(-5948 6000);
DISPLAY 0.872340 (-5948 6000);
PAINT GREEN (-5948 6000);
DISPLAY INVISIBLE (-5948 6000);
FORCEADD TAP..1
R 2
(-5950 5900);
FORCEPROP 3 LASTPIN (-5900 5900) SIG_NAME M_F_CPU1_SA_DQS_DN<2>
J 0
(-5890 5910);
DISPLAY 0.659574 (-5890 5910);
PAINT MONO (-5890 5910);
DISPLAY INVISIBLE (-5890 5910);
FORCEPROP 1 LASTPIN (-5900 5900) BN 2
J 2
(-5888 5908);
DISPLAY 0.489362 (-5888 5908);
PAINT GREEN (-5888 5908);
FORCEPROP 2 LAST CDS_LIB mstr_standard
J 2
(-5950 5900);
DISPLAY 0.723404 (-5950 5900);
PAINT MONO (-5950 5900);
DISPLAY INVISIBLE (-5950 5900);
FORCEPROP 1 LAST BODY_TYPE PLUMBING
J 2
(-5950 5950);
DISPLAY 0.872340 (-5950 5950);
PAINT GREEN (-5950 5950);
DISPLAY INVISIBLE (-5950 5950);
FORCEPROP 1 LAST HDL_TAP TRUE
J 2
(-6275 5775);
DISPLAY 0.872340 (-6275 5775);
DISPLAY INVISIBLE (-6275 5775);
FORCEPROP 1 LAST PATH I252
J 2
(-5948 5900);
DISPLAY 0.872340 (-5948 5900);
PAINT GREEN (-5948 5900);
DISPLAY INVISIBLE (-5948 5900);
FORCEADD TAP..1
R 2
(-5950 5800);
FORCEPROP 3 LASTPIN (-5900 5800) SIG_NAME M_F_CPU1_SA_DQS_DN<3>
J 0
(-5890 5810);
DISPLAY 0.659574 (-5890 5810);
PAINT MONO (-5890 5810);
DISPLAY INVISIBLE (-5890 5810);
FORCEPROP 1 LASTPIN (-5900 5800) BN 3
J 2
(-5888 5808);
DISPLAY 0.489362 (-5888 5808);
PAINT GREEN (-5888 5808);
FORCEPROP 2 LAST CDS_LIB mstr_standard
J 2
(-5950 5800);
DISPLAY 0.723404 (-5950 5800);
PAINT MONO (-5950 5800);
DISPLAY INVISIBLE (-5950 5800);
FORCEPROP 1 LAST BODY_TYPE PLUMBING
J 2
(-5950 5850);
DISPLAY 0.872340 (-5950 5850);
PAINT GREEN (-5950 5850);
DISPLAY INVISIBLE (-5950 5850);
FORCEPROP 1 LAST HDL_TAP TRUE
J 2
(-6275 5675);
DISPLAY 0.872340 (-6275 5675);
DISPLAY INVISIBLE (-6275 5675);
FORCEPROP 1 LAST PATH I253
J 2
(-5948 5800);
DISPLAY 0.872340 (-5948 5800);
PAINT GREEN (-5948 5800);
DISPLAY INVISIBLE (-5948 5800);
FORCEADD TAP..1
R 2
(-5950 5700);
FORCEPROP 3 LASTPIN (-5900 5700) SIG_NAME M_F_CPU1_SA_DQS_DN<4>
J 0
(-5890 5710);
DISPLAY 0.659574 (-5890 5710);
PAINT MONO (-5890 5710);
DISPLAY INVISIBLE (-5890 5710);
FORCEPROP 1 LASTPIN (-5900 5700) BN 4
J 2
(-5888 5708);
DISPLAY 0.489362 (-5888 5708);
PAINT GREEN (-5888 5708);
FORCEPROP 2 LAST CDS_LIB mstr_standard
J 2
(-5950 5700);
DISPLAY 0.723404 (-5950 5700);
PAINT MONO (-5950 5700);
DISPLAY INVISIBLE (-5950 5700);
FORCEPROP 1 LAST BODY_TYPE PLUMBING
J 2
(-5950 5750);
DISPLAY 0.872340 (-5950 5750);
PAINT GREEN (-5950 5750);
DISPLAY INVISIBLE (-5950 5750);
FORCEPROP 1 LAST HDL_TAP TRUE
J 2
(-6275 5575);
DISPLAY 0.872340 (-6275 5575);
DISPLAY INVISIBLE (-6275 5575);
FORCEPROP 1 LAST PATH I254
J 2
(-5948 5700);
DISPLAY 0.872340 (-5948 5700);
PAINT GREEN (-5948 5700);
DISPLAY INVISIBLE (-5948 5700);
FORCEADD TAP..1
R 2
(-5750 5550);
FORCEPROP 3 LASTPIN (-5700 5550) SIG_NAME M_F_CPU1_SA_DQS_DP<6>
J 0
(-5690 5560);
DISPLAY 0.659574 (-5690 5560);
PAINT MONO (-5690 5560);
DISPLAY INVISIBLE (-5690 5560);
FORCEPROP 1 LASTPIN (-5700 5550) BN 6
J 2
(-5688 5558);
DISPLAY 0.489362 (-5688 5558);
PAINT GREEN (-5688 5558);
FORCEPROP 2 LAST CDS_LIB mstr_standard
J 2
(-5750 5550);
DISPLAY 0.723404 (-5750 5550);
PAINT MONO (-5750 5550);
DISPLAY INVISIBLE (-5750 5550);
FORCEPROP 1 LAST BODY_TYPE PLUMBING
J 2
(-5750 5600);
DISPLAY 0.872340 (-5750 5600);
PAINT GREEN (-5750 5600);
DISPLAY INVISIBLE (-5750 5600);
FORCEPROP 1 LAST HDL_TAP TRUE
J 2
(-6075 5425);
DISPLAY 0.872340 (-6075 5425);
DISPLAY INVISIBLE (-6075 5425);
FORCEPROP 1 LAST PATH I255
J 2
(-5748 5550);
DISPLAY 0.872340 (-5748 5550);
PAINT GREEN (-5748 5550);
DISPLAY INVISIBLE (-5748 5550);
FORCEADD TAP..1
R 2
(-5750 5450);
FORCEPROP 3 LASTPIN (-5700 5450) SIG_NAME M_F_CPU1_SA_DQS_DP<7>
J 0
(-5690 5460);
DISPLAY 0.659574 (-5690 5460);
PAINT MONO (-5690 5460);
DISPLAY INVISIBLE (-5690 5460);
FORCEPROP 1 LASTPIN (-5700 5450) BN 7
J 2
(-5688 5458);
DISPLAY 0.489362 (-5688 5458);
PAINT GREEN (-5688 5458);
FORCEPROP 2 LAST CDS_LIB mstr_standard
J 2
(-5750 5450);
DISPLAY 0.723404 (-5750 5450);
PAINT MONO (-5750 5450);
DISPLAY INVISIBLE (-5750 5450);
FORCEPROP 1 LAST BODY_TYPE PLUMBING
J 2
(-5750 5500);
DISPLAY 0.872340 (-5750 5500);
PAINT GREEN (-5750 5500);
DISPLAY INVISIBLE (-5750 5500);
FORCEPROP 1 LAST HDL_TAP TRUE
J 2
(-6075 5325);
DISPLAY 0.872340 (-6075 5325);
DISPLAY INVISIBLE (-6075 5325);
FORCEPROP 1 LAST PATH I256
J 2
(-5748 5450);
DISPLAY 0.872340 (-5748 5450);
PAINT GREEN (-5748 5450);
DISPLAY INVISIBLE (-5748 5450);
FORCEADD TAP..1
R 2
(-5750 5250);
FORCEPROP 3 LASTPIN (-5700 5250) SIG_NAME M_F_CPU1_SA_DQS_DP<9>
J 0
(-5690 5260);
DISPLAY 0.659574 (-5690 5260);
PAINT MONO (-5690 5260);
DISPLAY INVISIBLE (-5690 5260);
FORCEPROP 1 LASTPIN (-5700 5250) BN 9
J 2
(-5688 5258);
DISPLAY 0.489362 (-5688 5258);
PAINT GREEN (-5688 5258);
FORCEPROP 2 LAST CDS_LIB mstr_standard
J 2
(-5750 5250);
DISPLAY 0.723404 (-5750 5250);
PAINT MONO (-5750 5250);
DISPLAY INVISIBLE (-5750 5250);
FORCEPROP 1 LAST BODY_TYPE PLUMBING
J 2
(-5750 5300);
DISPLAY 0.872340 (-5750 5300);
PAINT GREEN (-5750 5300);
DISPLAY INVISIBLE (-5750 5300);
FORCEPROP 1 LAST HDL_TAP TRUE
J 2
(-6075 5125);
DISPLAY 0.872340 (-6075 5125);
DISPLAY INVISIBLE (-6075 5125);
FORCEPROP 1 LAST PATH I257
J 2
(-5748 5250);
DISPLAY 0.872340 (-5748 5250);
PAINT GREEN (-5748 5250);
DISPLAY INVISIBLE (-5748 5250);
FORCEADD TAP..1
R 2
(-5750 5350);
FORCEPROP 3 LASTPIN (-5700 5350) SIG_NAME M_F_CPU1_SA_DQS_DP<8>
J 0
(-5690 5360);
DISPLAY 0.659574 (-5690 5360);
PAINT MONO (-5690 5360);
DISPLAY INVISIBLE (-5690 5360);
FORCEPROP 1 LASTPIN (-5700 5350) BN 8
J 2
(-5688 5358);
DISPLAY 0.489362 (-5688 5358);
PAINT GREEN (-5688 5358);
FORCEPROP 2 LAST CDS_LIB mstr_standard
J 2
(-5750 5350);
DISPLAY 0.723404 (-5750 5350);
PAINT MONO (-5750 5350);
DISPLAY INVISIBLE (-5750 5350);
FORCEPROP 1 LAST BODY_TYPE PLUMBING
J 2
(-5750 5400);
DISPLAY 0.872340 (-5750 5400);
PAINT GREEN (-5750 5400);
DISPLAY INVISIBLE (-5750 5400);
FORCEPROP 1 LAST HDL_TAP TRUE
J 2
(-6075 5225);
DISPLAY 0.872340 (-6075 5225);
DISPLAY INVISIBLE (-6075 5225);
FORCEPROP 1 LAST PATH I258
J 2
(-5748 5350);
DISPLAY 0.872340 (-5748 5350);
PAINT GREEN (-5748 5350);
DISPLAY INVISIBLE (-5748 5350);
FORCEADD TAP..1
R 2
(-5950 5600);
FORCEPROP 3 LASTPIN (-5900 5600) SIG_NAME M_F_CPU1_SA_DQS_DN<5>
J 0
(-5890 5610);
DISPLAY 0.659574 (-5890 5610);
PAINT MONO (-5890 5610);
DISPLAY INVISIBLE (-5890 5610);
FORCEPROP 1 LASTPIN (-5900 5600) BN 5
J 2
(-5888 5608);
DISPLAY 0.489362 (-5888 5608);
PAINT GREEN (-5888 5608);
FORCEPROP 2 LAST CDS_LIB mstr_standard
J 2
(-5950 5600);
DISPLAY 0.723404 (-5950 5600);
PAINT MONO (-5950 5600);
DISPLAY INVISIBLE (-5950 5600);
FORCEPROP 1 LAST BODY_TYPE PLUMBING
J 2
(-5950 5650);
DISPLAY 0.872340 (-5950 5650);
PAINT GREEN (-5950 5650);
DISPLAY INVISIBLE (-5950 5650);
FORCEPROP 1 LAST HDL_TAP TRUE
J 2
(-6275 5475);
DISPLAY 0.872340 (-6275 5475);
DISPLAY INVISIBLE (-6275 5475);
FORCEPROP 1 LAST PATH I259
J 2
(-5948 5600);
DISPLAY 0.872340 (-5948 5600);
PAINT GREEN (-5948 5600);
DISPLAY INVISIBLE (-5948 5600);
FORCEADD TAP..1
R 2
(-5950 5500);
FORCEPROP 3 LASTPIN (-5900 5500) SIG_NAME M_F_CPU1_SA_DQS_DN<6>
J 0
(-5890 5510);
DISPLAY 0.659574 (-5890 5510);
PAINT MONO (-5890 5510);
DISPLAY INVISIBLE (-5890 5510);
FORCEPROP 1 LASTPIN (-5900 5500) BN 6
J 2
(-5888 5508);
DISPLAY 0.489362 (-5888 5508);
PAINT GREEN (-5888 5508);
FORCEPROP 2 LAST CDS_LIB mstr_standard
J 2
(-5950 5500);
DISPLAY 0.723404 (-5950 5500);
PAINT MONO (-5950 5500);
DISPLAY INVISIBLE (-5950 5500);
FORCEPROP 1 LAST BODY_TYPE PLUMBING
J 2
(-5950 5550);
DISPLAY 0.872340 (-5950 5550);
PAINT GREEN (-5950 5550);
DISPLAY INVISIBLE (-5950 5550);
FORCEPROP 1 LAST HDL_TAP TRUE
J 2
(-6275 5375);
DISPLAY 0.872340 (-6275 5375);
DISPLAY INVISIBLE (-6275 5375);
FORCEPROP 1 LAST PATH I260
J 2
(-5948 5500);
DISPLAY 0.872340 (-5948 5500);
PAINT GREEN (-5948 5500);
DISPLAY INVISIBLE (-5948 5500);
FORCEADD TAP..1
R 2
(-5950 5400);
FORCEPROP 3 LASTPIN (-5900 5400) SIG_NAME M_F_CPU1_SA_DQS_DN<7>
J 0
(-5890 5410);
DISPLAY 0.659574 (-5890 5410);
PAINT MONO (-5890 5410);
DISPLAY INVISIBLE (-5890 5410);
FORCEPROP 1 LASTPIN (-5900 5400) BN 7
J 2
(-5888 5408);
DISPLAY 0.489362 (-5888 5408);
PAINT GREEN (-5888 5408);
FORCEPROP 2 LAST CDS_LIB mstr_standard
J 2
(-5950 5400);
DISPLAY 0.723404 (-5950 5400);
PAINT MONO (-5950 5400);
DISPLAY INVISIBLE (-5950 5400);
FORCEPROP 1 LAST BODY_TYPE PLUMBING
J 2
(-5950 5450);
DISPLAY 0.872340 (-5950 5450);
PAINT GREEN (-5950 5450);
DISPLAY INVISIBLE (-5950 5450);
FORCEPROP 1 LAST HDL_TAP TRUE
J 2
(-6275 5275);
DISPLAY 0.872340 (-6275 5275);
DISPLAY INVISIBLE (-6275 5275);
FORCEPROP 1 LAST PATH I261
J 2
(-5948 5400);
DISPLAY 0.872340 (-5948 5400);
PAINT GREEN (-5948 5400);
DISPLAY INVISIBLE (-5948 5400);
FORCEADD TAP..1
R 2
(-5950 5300);
FORCEPROP 3 LASTPIN (-5900 5300) SIG_NAME M_F_CPU1_SA_DQS_DN<8>
J 0
(-5890 5310);
DISPLAY 0.659574 (-5890 5310);
PAINT MONO (-5890 5310);
DISPLAY INVISIBLE (-5890 5310);
FORCEPROP 1 LASTPIN (-5900 5300) BN 8
J 2
(-5888 5308);
DISPLAY 0.489362 (-5888 5308);
PAINT GREEN (-5888 5308);
FORCEPROP 2 LAST CDS_LIB mstr_standard
J 2
(-5950 5300);
DISPLAY 0.723404 (-5950 5300);
PAINT MONO (-5950 5300);
DISPLAY INVISIBLE (-5950 5300);
FORCEPROP 1 LAST BODY_TYPE PLUMBING
J 2
(-5950 5350);
DISPLAY 0.872340 (-5950 5350);
PAINT GREEN (-5950 5350);
DISPLAY INVISIBLE (-5950 5350);
FORCEPROP 1 LAST HDL_TAP TRUE
J 2
(-6275 5175);
DISPLAY 0.872340 (-6275 5175);
DISPLAY INVISIBLE (-6275 5175);
FORCEPROP 1 LAST PATH I262
J 2
(-5948 5300);
DISPLAY 0.872340 (-5948 5300);
PAINT GREEN (-5948 5300);
DISPLAY INVISIBLE (-5948 5300);
FORCEADD TAP..1
R 2
(-5950 5200);
FORCEPROP 3 LASTPIN (-5900 5200) SIG_NAME M_F_CPU1_SA_DQS_DN<9>
J 0
(-5890 5210);
DISPLAY 0.659574 (-5890 5210);
PAINT MONO (-5890 5210);
DISPLAY INVISIBLE (-5890 5210);
FORCEPROP 1 LASTPIN (-5900 5200) BN 9
J 2
(-5888 5208);
DISPLAY 0.489362 (-5888 5208);
PAINT GREEN (-5888 5208);
FORCEPROP 2 LAST CDS_LIB mstr_standard
J 2
(-5950 5200);
DISPLAY 0.723404 (-5950 5200);
PAINT MONO (-5950 5200);
DISPLAY INVISIBLE (-5950 5200);
FORCEPROP 1 LAST BODY_TYPE PLUMBING
J 2
(-5950 5250);
DISPLAY 0.872340 (-5950 5250);
PAINT GREEN (-5950 5250);
DISPLAY INVISIBLE (-5950 5250);
FORCEPROP 1 LAST HDL_TAP TRUE
J 2
(-6275 5075);
DISPLAY 0.872340 (-6275 5075);
DISPLAY INVISIBLE (-6275 5075);
FORCEPROP 1 LAST PATH I263
J 2
(-5948 5200);
DISPLAY 0.872340 (-5948 5200);
PAINT GREEN (-5948 5200);
DISPLAY INVISIBLE (-5948 5200);
FORCEADD TAP..1
R 2
(-5750 5000);
FORCEPROP 3 LASTPIN (-5700 5000) SIG_NAME M_F_CPU1_SB_DQS_DP<1>
J 0
(-5690 5010);
DISPLAY 0.659574 (-5690 5010);
PAINT MONO (-5690 5010);
DISPLAY INVISIBLE (-5690 5010);
FORCEPROP 1 LASTPIN (-5700 5000) BN 1
J 2
(-5688 5008);
DISPLAY 0.489362 (-5688 5008);
PAINT GREEN (-5688 5008);
FORCEPROP 2 LAST CDS_LIB mstr_standard
J 2
(-5750 5000);
DISPLAY 0.723404 (-5750 5000);
PAINT MONO (-5750 5000);
DISPLAY INVISIBLE (-5750 5000);
FORCEPROP 1 LAST BODY_TYPE PLUMBING
J 2
(-5750 5050);
DISPLAY 0.872340 (-5750 5050);
PAINT GREEN (-5750 5050);
DISPLAY INVISIBLE (-5750 5050);
FORCEPROP 1 LAST HDL_TAP TRUE
J 2
(-6075 4875);
DISPLAY 0.872340 (-6075 4875);
DISPLAY INVISIBLE (-6075 4875);
FORCEPROP 1 LAST PATH I264
J 2
(-5748 5000);
DISPLAY 0.872340 (-5748 5000);
PAINT GREEN (-5748 5000);
DISPLAY INVISIBLE (-5748 5000);
FORCEADD TAP..1
R 2
(-5750 5100);
FORCEPROP 3 LASTPIN (-5700 5100) SIG_NAME M_F_CPU1_SB_DQS_DP<0>
J 0
(-5690 5110);
DISPLAY 0.659574 (-5690 5110);
PAINT MONO (-5690 5110);
DISPLAY INVISIBLE (-5690 5110);
FORCEPROP 1 LASTPIN (-5700 5100) BN 0
J 2
(-5688 5108);
DISPLAY 0.489362 (-5688 5108);
PAINT GREEN (-5688 5108);
FORCEPROP 2 LAST CDS_LIB mstr_standard
J 2
(-5750 5100);
DISPLAY 0.723404 (-5750 5100);
PAINT MONO (-5750 5100);
DISPLAY INVISIBLE (-5750 5100);
FORCEPROP 1 LAST BODY_TYPE PLUMBING
J 2
(-5750 5150);
DISPLAY 0.872340 (-5750 5150);
PAINT GREEN (-5750 5150);
DISPLAY INVISIBLE (-5750 5150);
FORCEPROP 1 LAST HDL_TAP TRUE
J 2
(-6075 4975);
DISPLAY 0.872340 (-6075 4975);
DISPLAY INVISIBLE (-6075 4975);
FORCEPROP 1 LAST PATH I265
J 2
(-5748 5100);
DISPLAY 0.872340 (-5748 5100);
PAINT GREEN (-5748 5100);
DISPLAY INVISIBLE (-5748 5100);
FORCEADD TAP..1
R 2
(-5750 4900);
FORCEPROP 3 LASTPIN (-5700 4900) SIG_NAME M_F_CPU1_SB_DQS_DP<2>
J 0
(-5690 4910);
DISPLAY 0.659574 (-5690 4910);
PAINT MONO (-5690 4910);
DISPLAY INVISIBLE (-5690 4910);
FORCEPROP 1 LASTPIN (-5700 4900) BN 2
J 2
(-5688 4908);
DISPLAY 0.489362 (-5688 4908);
PAINT GREEN (-5688 4908);
FORCEPROP 2 LAST CDS_LIB mstr_standard
J 2
(-5750 4900);
DISPLAY 0.723404 (-5750 4900);
PAINT MONO (-5750 4900);
DISPLAY INVISIBLE (-5750 4900);
FORCEPROP 1 LAST BODY_TYPE PLUMBING
J 2
(-5750 4950);
DISPLAY 0.872340 (-5750 4950);
PAINT GREEN (-5750 4950);
DISPLAY INVISIBLE (-5750 4950);
FORCEPROP 1 LAST HDL_TAP TRUE
J 2
(-6075 4775);
DISPLAY 0.872340 (-6075 4775);
DISPLAY INVISIBLE (-6075 4775);
FORCEPROP 1 LAST PATH I266
J 2
(-5748 4900);
DISPLAY 0.872340 (-5748 4900);
PAINT GREEN (-5748 4900);
DISPLAY INVISIBLE (-5748 4900);
FORCEADD TAP..1
R 2
(-5750 4800);
FORCEPROP 3 LASTPIN (-5700 4800) SIG_NAME M_F_CPU1_SB_DQS_DP<3>
J 0
(-5690 4810);
DISPLAY 0.659574 (-5690 4810);
PAINT MONO (-5690 4810);
DISPLAY INVISIBLE (-5690 4810);
FORCEPROP 1 LASTPIN (-5700 4800) BN 3
J 2
(-5688 4808);
DISPLAY 0.489362 (-5688 4808);
PAINT GREEN (-5688 4808);
FORCEPROP 2 LAST CDS_LIB mstr_standard
J 2
(-5750 4800);
DISPLAY 0.723404 (-5750 4800);
PAINT MONO (-5750 4800);
DISPLAY INVISIBLE (-5750 4800);
FORCEPROP 1 LAST BODY_TYPE PLUMBING
J 2
(-5750 4850);
DISPLAY 0.872340 (-5750 4850);
PAINT GREEN (-5750 4850);
DISPLAY INVISIBLE (-5750 4850);
FORCEPROP 1 LAST HDL_TAP TRUE
J 2
(-6075 4675);
DISPLAY 0.872340 (-6075 4675);
DISPLAY INVISIBLE (-6075 4675);
FORCEPROP 1 LAST PATH I267
J 2
(-5748 4800);
DISPLAY 0.872340 (-5748 4800);
PAINT GREEN (-5748 4800);
DISPLAY INVISIBLE (-5748 4800);
FORCEADD TAP..1
R 2
(-5750 4700);
FORCEPROP 3 LASTPIN (-5700 4700) SIG_NAME M_F_CPU1_SB_DQS_DP<4>
J 0
(-5690 4710);
DISPLAY 0.659574 (-5690 4710);
PAINT MONO (-5690 4710);
DISPLAY INVISIBLE (-5690 4710);
FORCEPROP 1 LASTPIN (-5700 4700) BN 4
J 2
(-5688 4708);
DISPLAY 0.489362 (-5688 4708);
PAINT GREEN (-5688 4708);
FORCEPROP 2 LAST CDS_LIB mstr_standard
J 2
(-5750 4700);
DISPLAY 0.723404 (-5750 4700);
PAINT MONO (-5750 4700);
DISPLAY INVISIBLE (-5750 4700);
FORCEPROP 1 LAST BODY_TYPE PLUMBING
J 2
(-5750 4750);
DISPLAY 0.872340 (-5750 4750);
PAINT GREEN (-5750 4750);
DISPLAY INVISIBLE (-5750 4750);
FORCEPROP 1 LAST HDL_TAP TRUE
J 2
(-6075 4575);
DISPLAY 0.872340 (-6075 4575);
DISPLAY INVISIBLE (-6075 4575);
FORCEPROP 1 LAST PATH I268
J 2
(-5748 4700);
DISPLAY 0.872340 (-5748 4700);
PAINT GREEN (-5748 4700);
DISPLAY INVISIBLE (-5748 4700);
FORCEADD TAP..1
R 2
(-5950 5050);
FORCEPROP 3 LASTPIN (-5900 5050) SIG_NAME M_F_CPU1_SB_DQS_DN<0>
J 0
(-5890 5060);
DISPLAY 0.659574 (-5890 5060);
PAINT MONO (-5890 5060);
DISPLAY INVISIBLE (-5890 5060);
FORCEPROP 1 LASTPIN (-5900 5050) BN 0
J 2
(-5888 5058);
DISPLAY 0.489362 (-5888 5058);
PAINT GREEN (-5888 5058);
FORCEPROP 2 LAST CDS_LIB mstr_standard
J 2
(-5950 5050);
DISPLAY 0.723404 (-5950 5050);
PAINT MONO (-5950 5050);
DISPLAY INVISIBLE (-5950 5050);
FORCEPROP 1 LAST BODY_TYPE PLUMBING
J 2
(-5950 5100);
DISPLAY 0.872340 (-5950 5100);
PAINT GREEN (-5950 5100);
DISPLAY INVISIBLE (-5950 5100);
FORCEPROP 1 LAST HDL_TAP TRUE
J 2
(-6275 4925);
DISPLAY 0.872340 (-6275 4925);
DISPLAY INVISIBLE (-6275 4925);
FORCEPROP 1 LAST PATH I269
J 2
(-5948 5050);
DISPLAY 0.872340 (-5948 5050);
PAINT GREEN (-5948 5050);
DISPLAY INVISIBLE (-5948 5050);
FORCEADD TAP..1
R 2
(-5950 4950);
FORCEPROP 3 LASTPIN (-5900 4950) SIG_NAME M_F_CPU1_SB_DQS_DN<1>
J 0
(-5890 4960);
DISPLAY 0.659574 (-5890 4960);
PAINT MONO (-5890 4960);
DISPLAY INVISIBLE (-5890 4960);
FORCEPROP 1 LASTPIN (-5900 4950) BN 1
J 2
(-5888 4958);
DISPLAY 0.489362 (-5888 4958);
PAINT GREEN (-5888 4958);
FORCEPROP 2 LAST CDS_LIB mstr_standard
J 2
(-5950 4950);
DISPLAY 0.723404 (-5950 4950);
PAINT MONO (-5950 4950);
DISPLAY INVISIBLE (-5950 4950);
FORCEPROP 1 LAST BODY_TYPE PLUMBING
J 2
(-5950 5000);
DISPLAY 0.872340 (-5950 5000);
PAINT GREEN (-5950 5000);
DISPLAY INVISIBLE (-5950 5000);
FORCEPROP 1 LAST HDL_TAP TRUE
J 2
(-6275 4825);
DISPLAY 0.872340 (-6275 4825);
DISPLAY INVISIBLE (-6275 4825);
FORCEPROP 1 LAST PATH I270
J 2
(-5948 4950);
DISPLAY 0.872340 (-5948 4950);
PAINT GREEN (-5948 4950);
DISPLAY INVISIBLE (-5948 4950);
FORCEADD TAP..1
R 2
(-5950 4850);
FORCEPROP 3 LASTPIN (-5900 4850) SIG_NAME M_F_CPU1_SB_DQS_DN<2>
J 0
(-5890 4860);
DISPLAY 0.659574 (-5890 4860);
PAINT MONO (-5890 4860);
DISPLAY INVISIBLE (-5890 4860);
FORCEPROP 1 LASTPIN (-5900 4850) BN 2
J 2
(-5888 4858);
DISPLAY 0.489362 (-5888 4858);
PAINT GREEN (-5888 4858);
FORCEPROP 2 LAST CDS_LIB mstr_standard
J 2
(-5950 4850);
DISPLAY 0.723404 (-5950 4850);
PAINT MONO (-5950 4850);
DISPLAY INVISIBLE (-5950 4850);
FORCEPROP 1 LAST BODY_TYPE PLUMBING
J 2
(-5950 4900);
DISPLAY 0.872340 (-5950 4900);
PAINT GREEN (-5950 4900);
DISPLAY INVISIBLE (-5950 4900);
FORCEPROP 1 LAST HDL_TAP TRUE
J 2
(-6275 4725);
DISPLAY 0.872340 (-6275 4725);
DISPLAY INVISIBLE (-6275 4725);
FORCEPROP 1 LAST PATH I271
J 2
(-5948 4850);
DISPLAY 0.872340 (-5948 4850);
PAINT GREEN (-5948 4850);
DISPLAY INVISIBLE (-5948 4850);
FORCEADD TAP..1
R 2
(-5950 4750);
FORCEPROP 3 LASTPIN (-5900 4750) SIG_NAME M_F_CPU1_SB_DQS_DN<3>
J 0
(-5890 4760);
DISPLAY 0.659574 (-5890 4760);
PAINT MONO (-5890 4760);
DISPLAY INVISIBLE (-5890 4760);
FORCEPROP 1 LASTPIN (-5900 4750) BN 3
J 2
(-5888 4758);
DISPLAY 0.489362 (-5888 4758);
PAINT GREEN (-5888 4758);
FORCEPROP 2 LAST CDS_LIB mstr_standard
J 2
(-5950 4750);
DISPLAY 0.723404 (-5950 4750);
PAINT MONO (-5950 4750);
DISPLAY INVISIBLE (-5950 4750);
FORCEPROP 1 LAST BODY_TYPE PLUMBING
J 2
(-5950 4800);
DISPLAY 0.872340 (-5950 4800);
PAINT GREEN (-5950 4800);
DISPLAY INVISIBLE (-5950 4800);
FORCEPROP 1 LAST HDL_TAP TRUE
J 2
(-6275 4625);
DISPLAY 0.872340 (-6275 4625);
DISPLAY INVISIBLE (-6275 4625);
FORCEPROP 1 LAST PATH I272
J 2
(-5948 4750);
DISPLAY 0.872340 (-5948 4750);
PAINT GREEN (-5948 4750);
DISPLAY INVISIBLE (-5948 4750);
FORCEADD TAP..1
R 2
(-5950 4650);
FORCEPROP 3 LASTPIN (-5900 4650) SIG_NAME M_F_CPU1_SB_DQS_DN<4>
J 0
(-5890 4660);
DISPLAY 0.659574 (-5890 4660);
PAINT MONO (-5890 4660);
DISPLAY INVISIBLE (-5890 4660);
FORCEPROP 1 LASTPIN (-5900 4650) BN 4
J 2
(-5888 4658);
DISPLAY 0.489362 (-5888 4658);
PAINT GREEN (-5888 4658);
FORCEPROP 2 LAST CDS_LIB mstr_standard
J 2
(-5950 4650);
DISPLAY 0.723404 (-5950 4650);
PAINT MONO (-5950 4650);
DISPLAY INVISIBLE (-5950 4650);
FORCEPROP 1 LAST BODY_TYPE PLUMBING
J 2
(-5950 4700);
DISPLAY 0.872340 (-5950 4700);
PAINT GREEN (-5950 4700);
DISPLAY INVISIBLE (-5950 4700);
FORCEPROP 1 LAST HDL_TAP TRUE
J 2
(-6275 4525);
DISPLAY 0.872340 (-6275 4525);
DISPLAY INVISIBLE (-6275 4525);
FORCEPROP 1 LAST PATH I273
J 2
(-5948 4650);
DISPLAY 0.872340 (-5948 4650);
PAINT GREEN (-5948 4650);
DISPLAY INVISIBLE (-5948 4650);
FORCEADD TAP..1
R 2
(-5750 4500);
FORCEPROP 3 LASTPIN (-5700 4500) SIG_NAME M_F_CPU1_SB_DQS_DP<6>
J 0
(-5690 4510);
DISPLAY 0.659574 (-5690 4510);
PAINT MONO (-5690 4510);
DISPLAY INVISIBLE (-5690 4510);
FORCEPROP 1 LASTPIN (-5700 4500) BN 6
J 2
(-5688 4508);
DISPLAY 0.489362 (-5688 4508);
PAINT GREEN (-5688 4508);
FORCEPROP 2 LAST CDS_LIB mstr_standard
J 2
(-5750 4500);
DISPLAY 0.723404 (-5750 4500);
PAINT MONO (-5750 4500);
DISPLAY INVISIBLE (-5750 4500);
FORCEPROP 1 LAST BODY_TYPE PLUMBING
J 2
(-5750 4550);
DISPLAY 0.872340 (-5750 4550);
PAINT GREEN (-5750 4550);
DISPLAY INVISIBLE (-5750 4550);
FORCEPROP 1 LAST HDL_TAP TRUE
J 2
(-6075 4375);
DISPLAY 0.872340 (-6075 4375);
DISPLAY INVISIBLE (-6075 4375);
FORCEPROP 1 LAST PATH I274
J 2
(-5748 4500);
DISPLAY 0.872340 (-5748 4500);
PAINT GREEN (-5748 4500);
DISPLAY INVISIBLE (-5748 4500);
FORCEADD TAP..1
R 2
(-5750 4600);
FORCEPROP 3 LASTPIN (-5700 4600) SIG_NAME M_F_CPU1_SB_DQS_DP<5>
J 0
(-5690 4610);
DISPLAY 0.659574 (-5690 4610);
PAINT MONO (-5690 4610);
DISPLAY INVISIBLE (-5690 4610);
FORCEPROP 1 LASTPIN (-5700 4600) BN 5
J 2
(-5688 4608);
DISPLAY 0.489362 (-5688 4608);
PAINT GREEN (-5688 4608);
FORCEPROP 2 LAST CDS_LIB mstr_standard
J 2
(-5750 4600);
DISPLAY 0.723404 (-5750 4600);
PAINT MONO (-5750 4600);
DISPLAY INVISIBLE (-5750 4600);
FORCEPROP 1 LAST BODY_TYPE PLUMBING
J 2
(-5750 4650);
DISPLAY 0.872340 (-5750 4650);
PAINT GREEN (-5750 4650);
DISPLAY INVISIBLE (-5750 4650);
FORCEPROP 1 LAST HDL_TAP TRUE
J 2
(-6075 4475);
DISPLAY 0.872340 (-6075 4475);
DISPLAY INVISIBLE (-6075 4475);
FORCEPROP 1 LAST PATH I275
J 2
(-5748 4600);
DISPLAY 0.872340 (-5748 4600);
PAINT GREEN (-5748 4600);
DISPLAY INVISIBLE (-5748 4600);
FORCEADD TAP..1
R 2
(-5750 4400);
FORCEPROP 3 LASTPIN (-5700 4400) SIG_NAME M_F_CPU1_SB_DQS_DP<7>
J 0
(-5690 4410);
DISPLAY 0.659574 (-5690 4410);
PAINT MONO (-5690 4410);
DISPLAY INVISIBLE (-5690 4410);
FORCEPROP 1 LASTPIN (-5700 4400) BN 7
J 2
(-5688 4408);
DISPLAY 0.489362 (-5688 4408);
PAINT GREEN (-5688 4408);
FORCEPROP 2 LAST CDS_LIB mstr_standard
J 2
(-5750 4400);
DISPLAY 0.723404 (-5750 4400);
PAINT MONO (-5750 4400);
DISPLAY INVISIBLE (-5750 4400);
FORCEPROP 1 LAST BODY_TYPE PLUMBING
J 2
(-5750 4450);
DISPLAY 0.872340 (-5750 4450);
PAINT GREEN (-5750 4450);
DISPLAY INVISIBLE (-5750 4450);
FORCEPROP 1 LAST HDL_TAP TRUE
J 2
(-6075 4275);
DISPLAY 0.872340 (-6075 4275);
DISPLAY INVISIBLE (-6075 4275);
FORCEPROP 1 LAST PATH I276
J 2
(-5748 4400);
DISPLAY 0.872340 (-5748 4400);
PAINT GREEN (-5748 4400);
DISPLAY INVISIBLE (-5748 4400);
FORCEADD TAP..1
R 2
(-5750 4300);
FORCEPROP 3 LASTPIN (-5700 4300) SIG_NAME M_F_CPU1_SB_DQS_DP<8>
J 0
(-5690 4310);
DISPLAY 0.659574 (-5690 4310);
PAINT MONO (-5690 4310);
DISPLAY INVISIBLE (-5690 4310);
FORCEPROP 1 LASTPIN (-5700 4300) BN 8
J 2
(-5688 4308);
DISPLAY 0.489362 (-5688 4308);
PAINT GREEN (-5688 4308);
FORCEPROP 2 LAST CDS_LIB mstr_standard
J 2
(-5750 4300);
DISPLAY 0.723404 (-5750 4300);
PAINT MONO (-5750 4300);
DISPLAY INVISIBLE (-5750 4300);
FORCEPROP 1 LAST BODY_TYPE PLUMBING
J 2
(-5750 4350);
DISPLAY 0.872340 (-5750 4350);
PAINT GREEN (-5750 4350);
DISPLAY INVISIBLE (-5750 4350);
FORCEPROP 1 LAST HDL_TAP TRUE
J 2
(-6075 4175);
DISPLAY 0.872340 (-6075 4175);
DISPLAY INVISIBLE (-6075 4175);
FORCEPROP 1 LAST PATH I277
J 2
(-5748 4300);
DISPLAY 0.872340 (-5748 4300);
PAINT GREEN (-5748 4300);
DISPLAY INVISIBLE (-5748 4300);
FORCEADD TAP..1
R 2
(-5750 4200);
FORCEPROP 3 LASTPIN (-5700 4200) SIG_NAME M_F_CPU1_SB_DQS_DP<9>
J 0
(-5690 4210);
DISPLAY 0.659574 (-5690 4210);
PAINT MONO (-5690 4210);
DISPLAY INVISIBLE (-5690 4210);
FORCEPROP 1 LASTPIN (-5700 4200) BN 9
J 2
(-5688 4208);
DISPLAY 0.489362 (-5688 4208);
PAINT GREEN (-5688 4208);
FORCEPROP 2 LAST CDS_LIB mstr_standard
J 2
(-5750 4200);
DISPLAY 0.723404 (-5750 4200);
PAINT MONO (-5750 4200);
DISPLAY INVISIBLE (-5750 4200);
FORCEPROP 1 LAST BODY_TYPE PLUMBING
J 2
(-5750 4250);
DISPLAY 0.872340 (-5750 4250);
PAINT GREEN (-5750 4250);
DISPLAY INVISIBLE (-5750 4250);
FORCEPROP 1 LAST HDL_TAP TRUE
J 2
(-6075 4075);
DISPLAY 0.872340 (-6075 4075);
DISPLAY INVISIBLE (-6075 4075);
FORCEPROP 1 LAST PATH I278
J 2
(-5748 4200);
DISPLAY 0.872340 (-5748 4200);
PAINT GREEN (-5748 4200);
DISPLAY INVISIBLE (-5748 4200);
FORCEADD TAP..1
R 2
(-5950 4550);
FORCEPROP 3 LASTPIN (-5900 4550) SIG_NAME M_F_CPU1_SB_DQS_DN<5>
J 0
(-5890 4560);
DISPLAY 0.659574 (-5890 4560);
PAINT MONO (-5890 4560);
DISPLAY INVISIBLE (-5890 4560);
FORCEPROP 1 LASTPIN (-5900 4550) BN 5
J 2
(-5888 4558);
DISPLAY 0.489362 (-5888 4558);
PAINT GREEN (-5888 4558);
FORCEPROP 2 LAST CDS_LIB mstr_standard
J 2
(-5950 4550);
DISPLAY 0.723404 (-5950 4550);
PAINT MONO (-5950 4550);
DISPLAY INVISIBLE (-5950 4550);
FORCEPROP 1 LAST BODY_TYPE PLUMBING
J 2
(-5950 4600);
DISPLAY 0.872340 (-5950 4600);
PAINT GREEN (-5950 4600);
DISPLAY INVISIBLE (-5950 4600);
FORCEPROP 1 LAST HDL_TAP TRUE
J 2
(-6275 4425);
DISPLAY 0.872340 (-6275 4425);
DISPLAY INVISIBLE (-6275 4425);
FORCEPROP 1 LAST PATH I279
J 2
(-5948 4550);
DISPLAY 0.872340 (-5948 4550);
PAINT GREEN (-5948 4550);
DISPLAY INVISIBLE (-5948 4550);
FORCEADD TAP..1
R 2
(-5950 4450);
FORCEPROP 3 LASTPIN (-5900 4450) SIG_NAME M_F_CPU1_SB_DQS_DN<6>
J 0
(-5890 4460);
DISPLAY 0.659574 (-5890 4460);
PAINT MONO (-5890 4460);
DISPLAY INVISIBLE (-5890 4460);
FORCEPROP 1 LASTPIN (-5900 4450) BN 6
J 2
(-5888 4458);
DISPLAY 0.489362 (-5888 4458);
PAINT GREEN (-5888 4458);
FORCEPROP 2 LAST CDS_LIB mstr_standard
J 2
(-5950 4450);
DISPLAY 0.723404 (-5950 4450);
PAINT MONO (-5950 4450);
DISPLAY INVISIBLE (-5950 4450);
FORCEPROP 1 LAST BODY_TYPE PLUMBING
J 2
(-5950 4500);
DISPLAY 0.872340 (-5950 4500);
PAINT GREEN (-5950 4500);
DISPLAY INVISIBLE (-5950 4500);
FORCEPROP 1 LAST HDL_TAP TRUE
J 2
(-6275 4325);
DISPLAY 0.872340 (-6275 4325);
DISPLAY INVISIBLE (-6275 4325);
FORCEPROP 1 LAST PATH I280
J 2
(-5948 4450);
DISPLAY 0.872340 (-5948 4450);
PAINT GREEN (-5948 4450);
DISPLAY INVISIBLE (-5948 4450);
FORCEADD TAP..1
R 2
(-5950 4350);
FORCEPROP 3 LASTPIN (-5900 4350) SIG_NAME M_F_CPU1_SB_DQS_DN<7>
J 0
(-5890 4360);
DISPLAY 0.659574 (-5890 4360);
PAINT MONO (-5890 4360);
DISPLAY INVISIBLE (-5890 4360);
FORCEPROP 1 LASTPIN (-5900 4350) BN 7
J 2
(-5888 4358);
DISPLAY 0.489362 (-5888 4358);
PAINT GREEN (-5888 4358);
FORCEPROP 2 LAST CDS_LIB mstr_standard
J 2
(-5950 4350);
DISPLAY 0.723404 (-5950 4350);
PAINT MONO (-5950 4350);
DISPLAY INVISIBLE (-5950 4350);
FORCEPROP 1 LAST BODY_TYPE PLUMBING
J 2
(-5950 4400);
DISPLAY 0.872340 (-5950 4400);
PAINT GREEN (-5950 4400);
DISPLAY INVISIBLE (-5950 4400);
FORCEPROP 1 LAST HDL_TAP TRUE
J 2
(-6275 4225);
DISPLAY 0.872340 (-6275 4225);
DISPLAY INVISIBLE (-6275 4225);
FORCEPROP 1 LAST PATH I281
J 2
(-5948 4350);
DISPLAY 0.872340 (-5948 4350);
PAINT GREEN (-5948 4350);
DISPLAY INVISIBLE (-5948 4350);
FORCEADD TAP..1
R 2
(-5950 4150);
FORCEPROP 3 LASTPIN (-5900 4150) SIG_NAME M_F_CPU1_SB_DQS_DN<9>
J 0
(-5890 4160);
DISPLAY 0.659574 (-5890 4160);
PAINT MONO (-5890 4160);
DISPLAY INVISIBLE (-5890 4160);
FORCEPROP 1 LASTPIN (-5900 4150) BN 9
J 2
(-5888 4158);
DISPLAY 0.489362 (-5888 4158);
PAINT GREEN (-5888 4158);
FORCEPROP 2 LAST CDS_LIB mstr_standard
J 2
(-5950 4150);
DISPLAY 0.723404 (-5950 4150);
PAINT MONO (-5950 4150);
DISPLAY INVISIBLE (-5950 4150);
FORCEPROP 1 LAST BODY_TYPE PLUMBING
J 2
(-5950 4200);
DISPLAY 0.872340 (-5950 4200);
PAINT GREEN (-5950 4200);
DISPLAY INVISIBLE (-5950 4200);
FORCEPROP 1 LAST HDL_TAP TRUE
J 2
(-6275 4025);
DISPLAY 0.872340 (-6275 4025);
DISPLAY INVISIBLE (-6275 4025);
FORCEPROP 1 LAST PATH I282
J 2
(-5948 4150);
DISPLAY 0.872340 (-5948 4150);
PAINT GREEN (-5948 4150);
DISPLAY INVISIBLE (-5948 4150);
FORCEADD TAP..1
R 2
(-5950 4250);
FORCEPROP 3 LASTPIN (-5900 4250) SIG_NAME M_F_CPU1_SB_DQS_DN<8>
J 0
(-5890 4260);
DISPLAY 0.659574 (-5890 4260);
PAINT MONO (-5890 4260);
DISPLAY INVISIBLE (-5890 4260);
FORCEPROP 1 LASTPIN (-5900 4250) BN 8
J 2
(-5888 4258);
DISPLAY 0.489362 (-5888 4258);
PAINT GREEN (-5888 4258);
FORCEPROP 2 LAST CDS_LIB mstr_standard
J 2
(-5950 4250);
DISPLAY 0.723404 (-5950 4250);
PAINT MONO (-5950 4250);
DISPLAY INVISIBLE (-5950 4250);
FORCEPROP 1 LAST BODY_TYPE PLUMBING
J 2
(-5950 4300);
DISPLAY 0.872340 (-5950 4300);
PAINT GREEN (-5950 4300);
DISPLAY INVISIBLE (-5950 4300);
FORCEPROP 1 LAST HDL_TAP TRUE
J 2
(-6275 4125);
DISPLAY 0.872340 (-6275 4125);
DISPLAY INVISIBLE (-6275 4125);
FORCEPROP 1 LAST PATH I283
J 2
(-5948 4250);
DISPLAY 0.872340 (-5948 4250);
PAINT GREEN (-5948 4250);
DISPLAY INVISIBLE (-5948 4250);
FORCEADD OFFPAGE..3
R 2
(-6650 6175);
FORCEPROP 2 LAST $XR0 102 
J 0
(-6930 6175);
DISPLAY 0.638298 (-6930 6175);
PAINT MONO (-6930 6175);
FORCEPROP 2 LAST PATH I284
J 0
(-6925 6225);
DISPLAY 1.021277 (-6925 6225);
DISPLAY INVISIBLE (-6925 6225);
FORCEPROP 1 LAST COMMENT_BODY TRUE
J 2
(-6600 6075);
DISPLAY 0.872340 (-6600 6075);
PAINT GREEN (-6600 6075);
DISPLAY INVISIBLE (-6600 6075);
FORCEPROP 1 LAST OFFPAGE TRUE
J 2
(-6975 6050);
DISPLAY 0.872340 (-6975 6050);
PAINT GREEN (-6975 6050);
DISPLAY INVISIBLE (-6975 6050);
FORCEPROP 2 LAST CDS_LIB standard
J 0
(-6650 6175);
DISPLAY INVISIBLE (-6650 6175);
FORCEADD OFFPAGE..3
R 2
(-6650 6125);
FORCEPROP 2 LAST $XR0 102 
J 0
(-6930 6125);
DISPLAY 0.638298 (-6930 6125);
PAINT MONO (-6930 6125);
FORCEPROP 2 LAST PATH I285
J 0
(-6925 6175);
DISPLAY 1.021277 (-6925 6175);
DISPLAY INVISIBLE (-6925 6175);
FORCEPROP 1 LAST COMMENT_BODY TRUE
J 2
(-6600 6025);
DISPLAY 0.872340 (-6600 6025);
PAINT GREEN (-6600 6025);
DISPLAY INVISIBLE (-6600 6025);
FORCEPROP 1 LAST OFFPAGE TRUE
J 2
(-6975 6000);
DISPLAY 0.872340 (-6975 6000);
PAINT GREEN (-6975 6000);
DISPLAY INVISIBLE (-6975 6000);
FORCEPROP 2 LAST CDS_LIB standard
J 0
(-6650 6125);
DISPLAY INVISIBLE (-6650 6125);
FORCEADD OFFPAGE..3
R 2
(-6650 5125);
FORCEPROP 2 LAST $XR0 102 
J 0
(-6930 5125);
DISPLAY 0.638298 (-6930 5125);
PAINT MONO (-6930 5125);
FORCEPROP 2 LAST PATH I286
J 0
(-6925 5175);
DISPLAY 1.021277 (-6925 5175);
DISPLAY INVISIBLE (-6925 5175);
FORCEPROP 1 LAST COMMENT_BODY TRUE
J 2
(-6600 5025);
DISPLAY 0.872340 (-6600 5025);
PAINT GREEN (-6600 5025);
DISPLAY INVISIBLE (-6600 5025);
FORCEPROP 1 LAST OFFPAGE TRUE
J 2
(-6975 5000);
DISPLAY 0.872340 (-6975 5000);
PAINT GREEN (-6975 5000);
DISPLAY INVISIBLE (-6975 5000);
FORCEPROP 2 LAST CDS_LIB standard
J 0
(-6650 5125);
DISPLAY INVISIBLE (-6650 5125);
FORCEADD OFFPAGE..3
R 2
(-6650 5075);
FORCEPROP 2 LAST $XR0 102 
J 0
(-6930 5075);
DISPLAY 0.638298 (-6930 5075);
PAINT MONO (-6930 5075);
FORCEPROP 2 LAST PATH I287
J 0
(-6925 5125);
DISPLAY 1.021277 (-6925 5125);
DISPLAY INVISIBLE (-6925 5125);
FORCEPROP 1 LAST COMMENT_BODY TRUE
J 2
(-6600 4975);
DISPLAY 0.872340 (-6600 4975);
PAINT GREEN (-6600 4975);
DISPLAY INVISIBLE (-6600 4975);
FORCEPROP 1 LAST OFFPAGE TRUE
J 2
(-6975 4950);
DISPLAY 0.872340 (-6975 4950);
PAINT GREEN (-6975 4950);
DISPLAY INVISIBLE (-6975 4950);
FORCEPROP 2 LAST CDS_LIB standard
J 0
(-6650 5075);
DISPLAY INVISIBLE (-6650 5075);
FORCEADD TAP..1
R 2
(-5950 3950);
FORCEPROP 3 LASTPIN (-5900 3950) SIG_NAME M_F_CPU1_SA_CA<1>
J 0
(-5890 3960);
DISPLAY 0.659574 (-5890 3960);
PAINT MONO (-5890 3960);
DISPLAY INVISIBLE (-5890 3960);
FORCEPROP 1 LASTPIN (-5900 3950) BN 1
J 2
(-5888 3958);
DISPLAY 0.489362 (-5888 3958);
PAINT GREEN (-5888 3958);
FORCEPROP 2 LAST CDS_LIB mstr_standard
J 0
(-5950 3950);
DISPLAY 0.723404 (-5950 3950);
PAINT MONO (-5950 3950);
DISPLAY INVISIBLE (-5950 3950);
FORCEPROP 1 LAST BODY_TYPE PLUMBING
J 2
(-5950 4000);
DISPLAY 0.872340 (-5950 4000);
PAINT GREEN (-5950 4000);
DISPLAY INVISIBLE (-5950 4000);
FORCEPROP 1 LAST HDL_TAP TRUE
J 2
(-6275 3825);
DISPLAY 0.872340 (-6275 3825);
DISPLAY INVISIBLE (-6275 3825);
FORCEPROP 1 LAST PATH I288
J 2
(-5948 3950);
DISPLAY 0.872340 (-5948 3950);
PAINT GREEN (-5948 3950);
DISPLAY INVISIBLE (-5948 3950);
FORCEADD TAP..1
R 2
(-5950 4000);
FORCEPROP 3 LASTPIN (-5900 4000) SIG_NAME M_F_CPU1_SA_CA<0>
J 0
(-5890 4010);
DISPLAY 0.659574 (-5890 4010);
PAINT MONO (-5890 4010);
DISPLAY INVISIBLE (-5890 4010);
FORCEPROP 1 LASTPIN (-5900 4000) BN 0
J 2
(-5888 4008);
DISPLAY 0.489362 (-5888 4008);
PAINT GREEN (-5888 4008);
FORCEPROP 2 LAST CDS_LIB mstr_standard
J 0
(-5950 4000);
DISPLAY 0.723404 (-5950 4000);
PAINT MONO (-5950 4000);
DISPLAY INVISIBLE (-5950 4000);
FORCEPROP 1 LAST BODY_TYPE PLUMBING
J 2
(-5950 4050);
DISPLAY 0.872340 (-5950 4050);
PAINT GREEN (-5950 4050);
DISPLAY INVISIBLE (-5950 4050);
FORCEPROP 1 LAST HDL_TAP TRUE
J 2
(-6275 3875);
DISPLAY 0.872340 (-6275 3875);
DISPLAY INVISIBLE (-6275 3875);
FORCEPROP 1 LAST PATH I289
J 2
(-5948 4000);
DISPLAY 0.872340 (-5948 4000);
PAINT GREEN (-5948 4000);
DISPLAY INVISIBLE (-5948 4000);
FORCEADD TAP..1
R 2
(-5950 3900);
FORCEPROP 3 LASTPIN (-5900 3900) SIG_NAME M_F_CPU1_SA_CA<2>
J 0
(-5890 3910);
DISPLAY 0.659574 (-5890 3910);
PAINT MONO (-5890 3910);
DISPLAY INVISIBLE (-5890 3910);
FORCEPROP 1 LASTPIN (-5900 3900) BN 2
J 2
(-5888 3908);
DISPLAY 0.489362 (-5888 3908);
PAINT GREEN (-5888 3908);
FORCEPROP 2 LAST CDS_LIB mstr_standard
J 0
(-5950 3900);
DISPLAY 0.723404 (-5950 3900);
PAINT MONO (-5950 3900);
DISPLAY INVISIBLE (-5950 3900);
FORCEPROP 1 LAST BODY_TYPE PLUMBING
J 2
(-5950 3950);
DISPLAY 0.872340 (-5950 3950);
PAINT GREEN (-5950 3950);
DISPLAY INVISIBLE (-5950 3950);
FORCEPROP 1 LAST HDL_TAP TRUE
J 2
(-6275 3775);
DISPLAY 0.872340 (-6275 3775);
DISPLAY INVISIBLE (-6275 3775);
FORCEPROP 1 LAST PATH I290
J 2
(-5948 3900);
DISPLAY 0.872340 (-5948 3900);
PAINT GREEN (-5948 3900);
DISPLAY INVISIBLE (-5948 3900);
FORCEADD TAP..1
R 2
(-5950 3850);
FORCEPROP 3 LASTPIN (-5900 3850) SIG_NAME M_F_CPU1_SA_CA<3>
J 0
(-5890 3860);
DISPLAY 0.659574 (-5890 3860);
PAINT MONO (-5890 3860);
DISPLAY INVISIBLE (-5890 3860);
FORCEPROP 1 LASTPIN (-5900 3850) BN 3
J 2
(-5888 3858);
DISPLAY 0.489362 (-5888 3858);
PAINT GREEN (-5888 3858);
FORCEPROP 2 LAST CDS_LIB mstr_standard
J 0
(-5950 3850);
DISPLAY 0.723404 (-5950 3850);
PAINT MONO (-5950 3850);
DISPLAY INVISIBLE (-5950 3850);
FORCEPROP 1 LAST BODY_TYPE PLUMBING
J 2
(-5950 3900);
DISPLAY 0.872340 (-5950 3900);
PAINT GREEN (-5950 3900);
DISPLAY INVISIBLE (-5950 3900);
FORCEPROP 1 LAST HDL_TAP TRUE
J 2
(-6275 3725);
DISPLAY 0.872340 (-6275 3725);
DISPLAY INVISIBLE (-6275 3725);
FORCEPROP 1 LAST PATH I291
J 2
(-5948 3850);
DISPLAY 0.872340 (-5948 3850);
PAINT GREEN (-5948 3850);
DISPLAY INVISIBLE (-5948 3850);
FORCEADD TAP..1
R 2
(-5950 3800);
FORCEPROP 3 LASTPIN (-5900 3800) SIG_NAME M_F_CPU1_SA_CA<4>
J 0
(-5890 3810);
DISPLAY 0.659574 (-5890 3810);
PAINT MONO (-5890 3810);
DISPLAY INVISIBLE (-5890 3810);
FORCEPROP 1 LASTPIN (-5900 3800) BN 4
J 2
(-5888 3808);
DISPLAY 0.489362 (-5888 3808);
PAINT GREEN (-5888 3808);
FORCEPROP 2 LAST CDS_LIB mstr_standard
J 0
(-5950 3800);
DISPLAY 0.723404 (-5950 3800);
PAINT MONO (-5950 3800);
DISPLAY INVISIBLE (-5950 3800);
FORCEPROP 1 LAST BODY_TYPE PLUMBING
J 2
(-5950 3850);
DISPLAY 0.872340 (-5950 3850);
PAINT GREEN (-5950 3850);
DISPLAY INVISIBLE (-5950 3850);
FORCEPROP 1 LAST HDL_TAP TRUE
J 2
(-6275 3675);
DISPLAY 0.872340 (-6275 3675);
DISPLAY INVISIBLE (-6275 3675);
FORCEPROP 1 LAST PATH I292
J 2
(-5948 3800);
DISPLAY 0.872340 (-5948 3800);
PAINT GREEN (-5948 3800);
DISPLAY INVISIBLE (-5948 3800);
FORCEADD TAP..1
R 2
(-5950 3750);
FORCEPROP 3 LASTPIN (-5900 3750) SIG_NAME M_F_CPU1_SA_CA<5>
J 0
(-5890 3760);
DISPLAY 0.659574 (-5890 3760);
PAINT MONO (-5890 3760);
DISPLAY INVISIBLE (-5890 3760);
FORCEPROP 1 LASTPIN (-5900 3750) BN 5
J 2
(-5888 3758);
DISPLAY 0.489362 (-5888 3758);
PAINT GREEN (-5888 3758);
FORCEPROP 2 LAST CDS_LIB mstr_standard
J 0
(-5950 3750);
DISPLAY 0.723404 (-5950 3750);
PAINT MONO (-5950 3750);
DISPLAY INVISIBLE (-5950 3750);
FORCEPROP 1 LAST BODY_TYPE PLUMBING
J 2
(-5950 3800);
DISPLAY 0.872340 (-5950 3800);
PAINT GREEN (-5950 3800);
DISPLAY INVISIBLE (-5950 3800);
FORCEPROP 1 LAST HDL_TAP TRUE
J 2
(-6275 3625);
DISPLAY 0.872340 (-6275 3625);
DISPLAY INVISIBLE (-6275 3625);
FORCEPROP 1 LAST PATH I293
J 2
(-5948 3750);
DISPLAY 0.872340 (-5948 3750);
PAINT GREEN (-5948 3750);
DISPLAY INVISIBLE (-5948 3750);
FORCEADD TAP..1
R 2
(-5950 3700);
FORCEPROP 3 LASTPIN (-5900 3700) SIG_NAME M_F_CPU1_SA_CA<6>
J 0
(-5890 3710);
DISPLAY 0.659574 (-5890 3710);
PAINT MONO (-5890 3710);
DISPLAY INVISIBLE (-5890 3710);
FORCEPROP 1 LASTPIN (-5900 3700) BN 6
J 2
(-5888 3708);
DISPLAY 0.489362 (-5888 3708);
PAINT GREEN (-5888 3708);
FORCEPROP 2 LAST CDS_LIB mstr_standard
J 0
(-5950 3700);
DISPLAY 0.723404 (-5950 3700);
PAINT MONO (-5950 3700);
DISPLAY INVISIBLE (-5950 3700);
FORCEPROP 1 LAST BODY_TYPE PLUMBING
J 2
(-5950 3750);
DISPLAY 0.872340 (-5950 3750);
PAINT GREEN (-5950 3750);
DISPLAY INVISIBLE (-5950 3750);
FORCEPROP 1 LAST HDL_TAP TRUE
J 2
(-6275 3575);
DISPLAY 0.872340 (-6275 3575);
DISPLAY INVISIBLE (-6275 3575);
FORCEPROP 1 LAST PATH I294
J 2
(-5948 3700);
DISPLAY 0.872340 (-5948 3700);
PAINT GREEN (-5948 3700);
DISPLAY INVISIBLE (-5948 3700);
FORCEADD TAP..1
R 2
(-5950 3600);
FORCEPROP 3 LASTPIN (-5900 3600) SIG_NAME M_F_CPU1_SB_CA<0>
J 0
(-5890 3610);
DISPLAY 0.659574 (-5890 3610);
PAINT MONO (-5890 3610);
DISPLAY INVISIBLE (-5890 3610);
FORCEPROP 1 LASTPIN (-5900 3600) BN 0
J 2
(-5888 3608);
DISPLAY 0.489362 (-5888 3608);
PAINT GREEN (-5888 3608);
FORCEPROP 2 LAST CDS_LIB mstr_standard
J 0
(-5950 3600);
DISPLAY 0.723404 (-5950 3600);
PAINT MONO (-5950 3600);
DISPLAY INVISIBLE (-5950 3600);
FORCEPROP 1 LAST BODY_TYPE PLUMBING
J 2
(-5950 3650);
DISPLAY 0.872340 (-5950 3650);
PAINT GREEN (-5950 3650);
DISPLAY INVISIBLE (-5950 3650);
FORCEPROP 1 LAST HDL_TAP TRUE
J 2
(-6275 3475);
DISPLAY 0.872340 (-6275 3475);
DISPLAY INVISIBLE (-6275 3475);
FORCEPROP 1 LAST PATH I295
J 2
(-5948 3600);
DISPLAY 0.872340 (-5948 3600);
PAINT GREEN (-5948 3600);
DISPLAY INVISIBLE (-5948 3600);
FORCEADD TAP..1
R 2
(-5950 3500);
FORCEPROP 3 LASTPIN (-5900 3500) SIG_NAME M_F_CPU1_SB_CA<2>
J 0
(-5890 3510);
DISPLAY 0.659574 (-5890 3510);
PAINT MONO (-5890 3510);
DISPLAY INVISIBLE (-5890 3510);
FORCEPROP 1 LASTPIN (-5900 3500) BN 2
J 2
(-5888 3508);
DISPLAY 0.489362 (-5888 3508);
PAINT GREEN (-5888 3508);
FORCEPROP 2 LAST CDS_LIB mstr_standard
J 0
(-5950 3500);
DISPLAY 0.723404 (-5950 3500);
PAINT MONO (-5950 3500);
DISPLAY INVISIBLE (-5950 3500);
FORCEPROP 1 LAST BODY_TYPE PLUMBING
J 2
(-5950 3550);
DISPLAY 0.872340 (-5950 3550);
PAINT GREEN (-5950 3550);
DISPLAY INVISIBLE (-5950 3550);
FORCEPROP 1 LAST HDL_TAP TRUE
J 2
(-6275 3375);
DISPLAY 0.872340 (-6275 3375);
DISPLAY INVISIBLE (-6275 3375);
FORCEPROP 1 LAST PATH I296
J 2
(-5948 3500);
DISPLAY 0.872340 (-5948 3500);
PAINT GREEN (-5948 3500);
DISPLAY INVISIBLE (-5948 3500);
FORCEADD TAP..1
R 2
(-5950 3550);
FORCEPROP 3 LASTPIN (-5900 3550) SIG_NAME M_F_CPU1_SB_CA<1>
J 0
(-5890 3560);
DISPLAY 0.659574 (-5890 3560);
PAINT MONO (-5890 3560);
DISPLAY INVISIBLE (-5890 3560);
FORCEPROP 1 LASTPIN (-5900 3550) BN 1
J 2
(-5888 3558);
DISPLAY 0.489362 (-5888 3558);
PAINT GREEN (-5888 3558);
FORCEPROP 2 LAST CDS_LIB mstr_standard
J 0
(-5950 3550);
DISPLAY 0.723404 (-5950 3550);
PAINT MONO (-5950 3550);
DISPLAY INVISIBLE (-5950 3550);
FORCEPROP 1 LAST BODY_TYPE PLUMBING
J 2
(-5950 3600);
DISPLAY 0.872340 (-5950 3600);
PAINT GREEN (-5950 3600);
DISPLAY INVISIBLE (-5950 3600);
FORCEPROP 1 LAST HDL_TAP TRUE
J 2
(-6275 3425);
DISPLAY 0.872340 (-6275 3425);
DISPLAY INVISIBLE (-6275 3425);
FORCEPROP 1 LAST PATH I297
J 2
(-5948 3550);
DISPLAY 0.872340 (-5948 3550);
PAINT GREEN (-5948 3550);
DISPLAY INVISIBLE (-5948 3550);
FORCEADD TAP..1
R 2
(-5950 3450);
FORCEPROP 3 LASTPIN (-5900 3450) SIG_NAME M_F_CPU1_SB_CA<3>
J 0
(-5890 3460);
DISPLAY 0.659574 (-5890 3460);
PAINT MONO (-5890 3460);
DISPLAY INVISIBLE (-5890 3460);
FORCEPROP 1 LASTPIN (-5900 3450) BN 3
J 2
(-5888 3458);
DISPLAY 0.489362 (-5888 3458);
PAINT GREEN (-5888 3458);
FORCEPROP 2 LAST CDS_LIB mstr_standard
J 0
(-5950 3450);
DISPLAY 0.723404 (-5950 3450);
PAINT MONO (-5950 3450);
DISPLAY INVISIBLE (-5950 3450);
FORCEPROP 1 LAST BODY_TYPE PLUMBING
J 2
(-5950 3500);
DISPLAY 0.872340 (-5950 3500);
PAINT GREEN (-5950 3500);
DISPLAY INVISIBLE (-5950 3500);
FORCEPROP 1 LAST HDL_TAP TRUE
J 2
(-6275 3325);
DISPLAY 0.872340 (-6275 3325);
DISPLAY INVISIBLE (-6275 3325);
FORCEPROP 1 LAST PATH I298
J 2
(-5948 3450);
DISPLAY 0.872340 (-5948 3450);
PAINT GREEN (-5948 3450);
DISPLAY INVISIBLE (-5948 3450);
FORCEADD TAP..1
R 2
(-5950 3400);
FORCEPROP 3 LASTPIN (-5900 3400) SIG_NAME M_F_CPU1_SB_CA<4>
J 0
(-5890 3410);
DISPLAY 0.659574 (-5890 3410);
PAINT MONO (-5890 3410);
DISPLAY INVISIBLE (-5890 3410);
FORCEPROP 1 LASTPIN (-5900 3400) BN 4
J 2
(-5888 3408);
DISPLAY 0.489362 (-5888 3408);
PAINT GREEN (-5888 3408);
FORCEPROP 2 LAST CDS_LIB mstr_standard
J 0
(-5950 3400);
DISPLAY 0.723404 (-5950 3400);
PAINT MONO (-5950 3400);
DISPLAY INVISIBLE (-5950 3400);
FORCEPROP 1 LAST BODY_TYPE PLUMBING
J 2
(-5950 3450);
DISPLAY 0.872340 (-5950 3450);
PAINT GREEN (-5950 3450);
DISPLAY INVISIBLE (-5950 3450);
FORCEPROP 1 LAST HDL_TAP TRUE
J 2
(-6275 3275);
DISPLAY 0.872340 (-6275 3275);
DISPLAY INVISIBLE (-6275 3275);
FORCEPROP 1 LAST PATH I299
J 2
(-5948 3400);
DISPLAY 0.872340 (-5948 3400);
PAINT GREEN (-5948 3400);
DISPLAY INVISIBLE (-5948 3400);
FORCEADD TAP..1
R 2
(-5950 3350);
FORCEPROP 3 LASTPIN (-5900 3350) SIG_NAME M_F_CPU1_SB_CA<5>
J 0
(-5890 3360);
DISPLAY 0.659574 (-5890 3360);
PAINT MONO (-5890 3360);
DISPLAY INVISIBLE (-5890 3360);
FORCEPROP 1 LASTPIN (-5900 3350) BN 5
J 2
(-5888 3358);
DISPLAY 0.489362 (-5888 3358);
PAINT GREEN (-5888 3358);
FORCEPROP 2 LAST CDS_LIB mstr_standard
J 0
(-5950 3350);
DISPLAY 0.723404 (-5950 3350);
PAINT MONO (-5950 3350);
DISPLAY INVISIBLE (-5950 3350);
FORCEPROP 1 LAST BODY_TYPE PLUMBING
J 2
(-5950 3400);
DISPLAY 0.872340 (-5950 3400);
PAINT GREEN (-5950 3400);
DISPLAY INVISIBLE (-5950 3400);
FORCEPROP 1 LAST HDL_TAP TRUE
J 2
(-6275 3225);
DISPLAY 0.872340 (-6275 3225);
DISPLAY INVISIBLE (-6275 3225);
FORCEPROP 1 LAST PATH I300
J 2
(-5948 3350);
DISPLAY 0.872340 (-5948 3350);
PAINT GREEN (-5948 3350);
DISPLAY INVISIBLE (-5948 3350);
FORCEADD TAP..1
R 2
(-5950 3300);
FORCEPROP 3 LASTPIN (-5900 3300) SIG_NAME M_F_CPU1_SB_CA<6>
J 0
(-5890 3310);
DISPLAY 0.659574 (-5890 3310);
PAINT MONO (-5890 3310);
DISPLAY INVISIBLE (-5890 3310);
FORCEPROP 1 LASTPIN (-5900 3300) BN 6
J 2
(-5888 3308);
DISPLAY 0.489362 (-5888 3308);
PAINT GREEN (-5888 3308);
FORCEPROP 2 LAST CDS_LIB mstr_standard
J 0
(-5950 3300);
DISPLAY 0.723404 (-5950 3300);
PAINT MONO (-5950 3300);
DISPLAY INVISIBLE (-5950 3300);
FORCEPROP 1 LAST BODY_TYPE PLUMBING
J 2
(-5950 3350);
DISPLAY 0.872340 (-5950 3350);
PAINT GREEN (-5950 3350);
DISPLAY INVISIBLE (-5950 3350);
FORCEPROP 1 LAST HDL_TAP TRUE
J 2
(-6275 3175);
DISPLAY 0.872340 (-6275 3175);
DISPLAY INVISIBLE (-6275 3175);
FORCEPROP 1 LAST PATH I301
J 2
(-5948 3300);
DISPLAY 0.872340 (-5948 3300);
PAINT GREEN (-5948 3300);
DISPLAY INVISIBLE (-5948 3300);
FORCEADD OFFPAGE..2
R 2
(-6550 4025);
FORCEPROP 2 LAST $XR0 102 
J 0
(-6805 4025);
DISPLAY 0.638298 (-6805 4025);
PAINT MONO (-6805 4025);
FORCEPROP 2 LAST PATH I302
J 0
(-6800 4075);
DISPLAY 1.021277 (-6800 4075);
DISPLAY INVISIBLE (-6800 4075);
FORCEPROP 1 LAST COMMENT_BODY TRUE
J 2
(-6505 3930);
DISPLAY 0.872340 (-6505 3930);
PAINT GREEN (-6505 3930);
DISPLAY INVISIBLE (-6505 3930);
FORCEPROP 1 LAST OFFPAGE TRUE
J 2
(-6875 3900);
DISPLAY 0.872340 (-6875 3900);
PAINT GREEN (-6875 3900);
DISPLAY INVISIBLE (-6875 3900);
FORCEPROP 2 LAST CDS_LIB standard
J 0
(-6550 4025);
DISPLAY INVISIBLE (-6550 4025);
FORCEADD OFFPAGE..2
R 2
(-6550 3625);
FORCEPROP 2 LAST $XR0 102 
J 0
(-6805 3625);
DISPLAY 0.638298 (-6805 3625);
PAINT MONO (-6805 3625);
FORCEPROP 2 LAST PATH I303
J 0
(-6800 3675);
DISPLAY 1.021277 (-6800 3675);
DISPLAY INVISIBLE (-6800 3675);
FORCEPROP 1 LAST COMMENT_BODY TRUE
J 2
(-6505 3530);
DISPLAY 0.872340 (-6505 3530);
PAINT GREEN (-6505 3530);
DISPLAY INVISIBLE (-6505 3530);
FORCEPROP 1 LAST OFFPAGE TRUE
J 2
(-6875 3500);
DISPLAY 0.872340 (-6875 3500);
PAINT GREEN (-6875 3500);
DISPLAY INVISIBLE (-6875 3500);
FORCEPROP 2 LAST CDS_LIB standard
J 0
(-6550 3625);
DISPLAY INVISIBLE (-6550 3625);
FORCEADD OFFPAGE..2
R 2
(-6550 3150);
FORCEPROP 2 LAST $XR0 102 
J 0
(-6805 3150);
DISPLAY 0.638298 (-6805 3150);
PAINT MONO (-6805 3150);
FORCEPROP 2 LAST PATH I304
J 0
(-6800 3200);
DISPLAY 1.021277 (-6800 3200);
DISPLAY INVISIBLE (-6800 3200);
FORCEPROP 1 LAST COMMENT_BODY TRUE
J 2
(-6505 3055);
DISPLAY 0.872340 (-6505 3055);
PAINT GREEN (-6505 3055);
DISPLAY INVISIBLE (-6505 3055);
FORCEPROP 1 LAST OFFPAGE TRUE
J 2
(-6875 3025);
DISPLAY 0.872340 (-6875 3025);
PAINT GREEN (-6875 3025);
DISPLAY INVISIBLE (-6875 3025);
FORCEPROP 2 LAST CDS_LIB standard
J 0
(-6550 3150);
DISPLAY INVISIBLE (-6550 3150);
FORCEADD OFFPAGE..2
R 2
(-6550 3100);
FORCEPROP 2 LAST $XR0 102 
J 0
(-6805 3100);
DISPLAY 0.638298 (-6805 3100);
PAINT MONO (-6805 3100);
FORCEPROP 2 LAST PATH I305
J 0
(-6800 3150);
DISPLAY 1.021277 (-6800 3150);
DISPLAY INVISIBLE (-6800 3150);
FORCEPROP 1 LAST COMMENT_BODY TRUE
J 2
(-6505 3005);
DISPLAY 0.872340 (-6505 3005);
PAINT GREEN (-6505 3005);
DISPLAY INVISIBLE (-6505 3005);
FORCEPROP 1 LAST OFFPAGE TRUE
J 2
(-6875 2975);
DISPLAY 0.872340 (-6875 2975);
PAINT GREEN (-6875 2975);
DISPLAY INVISIBLE (-6875 2975);
FORCEPROP 2 LAST CDS_LIB standard
J 0
(-6550 3100);
DISPLAY INVISIBLE (-6550 3100);
FORCEADD OFFPAGE..2
R 2
(-6550 3000);
FORCEPROP 2 LAST $XR0 102 
J 0
(-6805 3000);
DISPLAY 0.638298 (-6805 3000);
PAINT MONO (-6805 3000);
FORCEPROP 2 LAST PATH I306
J 0
(-6800 3050);
DISPLAY 1.021277 (-6800 3050);
DISPLAY INVISIBLE (-6800 3050);
FORCEPROP 1 LAST COMMENT_BODY TRUE
J 2
(-6505 2905);
DISPLAY 0.872340 (-6505 2905);
PAINT GREEN (-6505 2905);
DISPLAY INVISIBLE (-6505 2905);
FORCEPROP 1 LAST OFFPAGE TRUE
J 2
(-6875 2875);
DISPLAY 0.872340 (-6875 2875);
PAINT GREEN (-6875 2875);
DISPLAY INVISIBLE (-6875 2875);
FORCEPROP 2 LAST CDS_LIB standard
J 0
(-6550 3000);
DISPLAY INVISIBLE (-6550 3000);
FORCEADD OFFPAGE..2
R 2
(-6550 2950);
FORCEPROP 2 LAST $XR0 102 
J 0
(-6805 2950);
DISPLAY 0.638298 (-6805 2950);
PAINT MONO (-6805 2950);
FORCEPROP 2 LAST PATH I307
J 0
(-6800 3000);
DISPLAY 1.021277 (-6800 3000);
DISPLAY INVISIBLE (-6800 3000);
FORCEPROP 1 LAST COMMENT_BODY TRUE
J 2
(-6505 2855);
DISPLAY 0.872340 (-6505 2855);
PAINT GREEN (-6505 2855);
DISPLAY INVISIBLE (-6505 2855);
FORCEPROP 1 LAST OFFPAGE TRUE
J 2
(-6875 2825);
DISPLAY 0.872340 (-6875 2825);
PAINT GREEN (-6875 2825);
DISPLAY INVISIBLE (-6875 2825);
FORCEPROP 2 LAST CDS_LIB standard
J 0
(-6550 2950);
DISPLAY INVISIBLE (-6550 2950);
FORCEADD OFFPAGE..1
(-6550 2850);
FORCEPROP 2 LAST $XR0 102 
J 0
(-6832 2850);
DISPLAY 0.638298 (-6832 2850);
PAINT MONO (-6832 2850);
FORCEPROP 2 LAST PATH I308
J 0
(-6825 2900);
DISPLAY 1.021277 (-6825 2900);
DISPLAY INVISIBLE (-6825 2900);
FORCEPROP 1 LAST COMMENT_BODY TRUE
J 0
(-6425 2750);
DISPLAY 0.872340 (-6425 2750);
PAINT GREEN (-6425 2750);
DISPLAY INVISIBLE (-6425 2750);
FORCEPROP 1 LAST OFFPAGE TRUE
J 0
(-6225 2725);
DISPLAY 0.872340 (-6225 2725);
PAINT GREEN (-6225 2725);
DISPLAY INVISIBLE (-6225 2725);
FORCEPROP 2 LAST CDS_LIB standard
J 0
(-6550 2850);
DISPLAY INVISIBLE (-6550 2850);
FORCEADD OFFPAGE..5
(-6550 2750);
FORCEPROP 2 LAST $XR0 102 
J 0
(-6805 2750);
DISPLAY 0.638298 (-6805 2750);
PAINT MONO (-6805 2750);
FORCEPROP 2 LAST PATH I309
J 0
(-6800 2800);
DISPLAY 1.021277 (-6800 2800);
DISPLAY INVISIBLE (-6800 2800);
FORCEPROP 1 LAST COMMENT_BODY TRUE
J 0
(-6450 2675);
DISPLAY 0.872340 (-6450 2675);
PAINT GREEN (-6450 2675);
DISPLAY INVISIBLE (-6450 2675);
FORCEPROP 1 LAST OFFPAGE TRUE
J 0
(-6225 2625);
DISPLAY 0.872340 (-6225 2625);
PAINT GREEN (-6225 2625);
DISPLAY INVISIBLE (-6225 2625);
FORCEPROP 2 LAST CDS_LIB mstr_standard
J 0
(-6550 2750);
DISPLAY INVISIBLE (-6550 2750);
FORCEADD OFFPAGE..2
R 2
(-6550 2650);
FORCEPROP 2 LAST $XR0 102 
J 0
(-6805 2650);
DISPLAY 0.638298 (-6805 2650);
PAINT MONO (-6805 2650);
FORCEPROP 2 LAST PATH I310
J 0
(-6800 2700);
DISPLAY 1.021277 (-6800 2700);
DISPLAY INVISIBLE (-6800 2700);
FORCEPROP 1 LAST COMMENT_BODY TRUE
J 2
(-6505 2555);
DISPLAY 0.872340 (-6505 2555);
PAINT GREEN (-6505 2555);
DISPLAY INVISIBLE (-6505 2555);
FORCEPROP 1 LAST OFFPAGE TRUE
J 2
(-6875 2525);
DISPLAY 0.872340 (-6875 2525);
PAINT GREEN (-6875 2525);
DISPLAY INVISIBLE (-6875 2525);
FORCEPROP 2 LAST CDS_LIB standard
J 0
(-6550 2650);
DISPLAY INVISIBLE (-6550 2650);
FORCEADD OFFPAGE..2
R 2
(-6550 2600);
FORCEPROP 2 LAST $XR0 102 
J 0
(-6805 2600);
DISPLAY 0.638298 (-6805 2600);
PAINT MONO (-6805 2600);
FORCEPROP 2 LAST PATH I311
J 0
(-6800 2650);
DISPLAY 1.021277 (-6800 2650);
DISPLAY INVISIBLE (-6800 2650);
FORCEPROP 1 LAST COMMENT_BODY TRUE
J 2
(-6505 2505);
DISPLAY 0.872340 (-6505 2505);
PAINT GREEN (-6505 2505);
DISPLAY INVISIBLE (-6505 2505);
FORCEPROP 1 LAST OFFPAGE TRUE
J 2
(-6875 2475);
DISPLAY 0.872340 (-6875 2475);
PAINT GREEN (-6875 2475);
DISPLAY INVISIBLE (-6875 2475);
FORCEPROP 2 LAST CDS_LIB standard
J 0
(-6550 2600);
DISPLAY INVISIBLE (-6550 2600);
FORCEADD OFFPAGE..1
(-6550 2500);
FORCEPROP 2 LAST $XR0 102 
J 0
(-6832 2500);
DISPLAY 0.638298 (-6832 2500);
PAINT MONO (-6832 2500);
FORCEPROP 2 LAST PATH I312
J 0
(-6825 2550);
DISPLAY 1.021277 (-6825 2550);
DISPLAY INVISIBLE (-6825 2550);
FORCEPROP 1 LAST COMMENT_BODY TRUE
J 0
(-6425 2400);
DISPLAY 0.872340 (-6425 2400);
PAINT GREEN (-6425 2400);
DISPLAY INVISIBLE (-6425 2400);
FORCEPROP 1 LAST OFFPAGE TRUE
J 0
(-6225 2375);
DISPLAY 0.872340 (-6225 2375);
PAINT GREEN (-6225 2375);
DISPLAY INVISIBLE (-6225 2375);
FORCEPROP 2 LAST CDS_LIB standard
J 0
(-6550 2500);
DISPLAY INVISIBLE (-6550 2500);
FORCEADD OFFPAGE..5
(-6550 2400);
FORCEPROP 2 LAST $XR0 102 
J 0
(-6805 2400);
DISPLAY 0.638298 (-6805 2400);
PAINT MONO (-6805 2400);
FORCEPROP 2 LAST PATH I313
J 0
(-6800 2450);
DISPLAY 1.021277 (-6800 2450);
DISPLAY INVISIBLE (-6800 2450);
FORCEPROP 1 LAST COMMENT_BODY TRUE
J 0
(-6450 2325);
DISPLAY 0.872340 (-6450 2325);
PAINT GREEN (-6450 2325);
DISPLAY INVISIBLE (-6450 2325);
FORCEPROP 1 LAST OFFPAGE TRUE
J 0
(-6225 2275);
DISPLAY 0.872340 (-6225 2275);
PAINT GREEN (-6225 2275);
DISPLAY INVISIBLE (-6225 2275);
FORCEPROP 2 LAST CDS_LIB standard
J 0
(-6550 2400);
DISPLAY INVISIBLE (-6550 2400);
FORCEADD Q_RES..1
(-6625 2300);
FORCEPROP 1 LAST LOCATION R505
J 0
(-6950 2300);
DISPLAY 0.489362 (-6950 2300);
PAINT SKYBLUE (-6950 2300);
FORCEPROP 0 LAST $SEC 1
J 0
(-6800 2350);
DISPLAY 0.680851 (-6800 2350);
PAINT MONO (-6800 2350);
DISPLAY INVISIBLE (-6800 2350);
FORCEPROP 0 LAST CDS_SEC 1
J 0
(-6800 2350);
DISPLAY 1.021277 (-6800 2350);
DISPLAY INVISIBLE (-6800 2350);
FORCEPROP 1 LASTPIN (-6725 2300) $PN 1
J 0
(-6713 2312);
DISPLAY 0.489362 (-6713 2312);
PAINT MONO (-6713 2312);
FORCEPROP 1 LASTPIN (-6525 2300) $PN 2
J 0
(-6563 2312);
DISPLAY 0.489362 (-6563 2312);
PAINT MONO (-6563 2312);
FORCEPROP 1 LAST TOLERANCE 1%
J 0
(-6350 2300);
DISPLAY 0.489362 (-6350 2300);
PAINT SKYBLUE (-6350 2300);
FORCEPROP 1 LAST VALUE 15   
J 2
(-6300 2300);
DISPLAY 0.489362 (-6300 2300);
PAINT SKYBLUE (-6300 2300);
FORCEPROP 1 LAST PART_NUMBER CS01502FB11
J 0
(-6500 2275);
DISPLAY 0.489362 (-6500 2275);
PAINT SKYBLUE (-6500 2275);
FORCEPROP 1 LAST PACK_TYPE 0402LF
J 0
(-6950 2275);
DISPLAY 0.489362 (-6950 2275);
PAINT SKYBLUE (-6950 2275);
FORCEPROP 2 LAST CDS_LIB pure_quanta
J 0
(-6625 2300);
DISPLAY INVISIBLE (-6625 2300);
FORCEPROP 1 LAST PATH I314
J 0
(-6675 2450);
DISPLAY 0.978723 (-6675 2450);
PAINT WHITE (-6675 2450);
DISPLAY INVISIBLE (-6675 2450);
FORCEPROP 1 LAST WATTAGE 1/16W
J 2
(-6400 2425);
DISPLAY 0.638298 (-6400 2425);
PAINT SKYBLUE (-6400 2425);
DISPLAY INVISIBLE (-6400 2425);
FORCEPROP 1 LAST MATERIAL CHIP
J 0
(-6750 2425);
DISPLAY 0.638298 (-6750 2425);
PAINT SKYBLUE (-6750 2425);
DISPLAY INVISIBLE (-6750 2425);
FORCEADD OFFPAGE..5
(-6550 2200);
FORCEPROP 2 LAST $XR0 102 
J 0
(-6805 2200);
DISPLAY 0.638298 (-6805 2200);
PAINT MONO (-6805 2200);
FORCEPROP 2 LAST PATH I315
J 0
(-6800 2250);
DISPLAY 1.021277 (-6800 2250);
DISPLAY INVISIBLE (-6800 2250);
FORCEPROP 1 LAST COMMENT_BODY TRUE
J 0
(-6450 2125);
DISPLAY 0.872340 (-6450 2125);
PAINT GREEN (-6450 2125);
DISPLAY INVISIBLE (-6450 2125);
FORCEPROP 1 LAST OFFPAGE TRUE
J 0
(-6225 2075);
DISPLAY 0.872340 (-6225 2075);
PAINT GREEN (-6225 2075);
DISPLAY INVISIBLE (-6225 2075);
FORCEPROP 2 LAST CDS_LIB standard
J 0
(-6550 2200);
DISPLAY INVISIBLE (-6550 2200);
FORCEADD OFFPAGE..1
(-7500 2300);
FORCEPROP 2 LAST $XR0 102 
J 0
(-7752 2300);
DISPLAY 0.638298 (-7752 2300);
PAINT MONO (-7752 2300);
FORCEPROP 2 LAST PATH I316
J 0
(-7750 2350);
DISPLAY 1.021277 (-7750 2350);
DISPLAY INVISIBLE (-7750 2350);
FORCEPROP 1 LAST COMMENT_BODY TRUE
J 0
(-7375 2200);
DISPLAY 0.872340 (-7375 2200);
PAINT GREEN (-7375 2200);
DISPLAY INVISIBLE (-7375 2200);
FORCEPROP 1 LAST OFFPAGE TRUE
J 0
(-7175 2175);
DISPLAY 0.872340 (-7175 2175);
PAINT GREEN (-7175 2175);
DISPLAY INVISIBLE (-7175 2175);
FORCEPROP 2 LAST CDS_LIB mstr_standard
J 0
(-7500 2300);
DISPLAY INVISIBLE (-7500 2300);
FORCEADD CAD_NOTE..1
(-7700 2575);
FORCEPROP 0 LAST L1 R1963 PLACE CLOSE TO CPU < 25MM
J 0
(-7850 2450);
DISPLAY 0.617021 (-7850 2450);
PAINT WHITE (-7850 2450);
FORCEPROP 2 LAST CDS_LIB pure_quanta_power
J 0
(-7700 2575);
DISPLAY INVISIBLE (-7700 2575);
FORCEPROP 1 LAST COMMENT_BODY TRUE
J 0
(-7675 2675);
DISPLAY 0.574468 (-7675 2675);
PAINT WHITE (-7675 2675);
DISPLAY INVISIBLE (-7675 2675);
FORCEADD QUANTA_TITLE_BLOCK_C..1
(-100 100);
FORCEPROP 0 LAST CDS_CON_LAST_MODIFIED Fri Mar 11 14:52:31 2022
J 0
(-1985 115);
DISPLAY INVISIBLE (-1985 115);
FORCEPROP 1 LAST CUSTOM_TXT_CDS <CON_LAST_MODIFIED>
J 0
(-1985 115);
DISPLAY 0.978723 (-1985 115);
FORCEPROP 2 LAST CUSTOM_TXT_CDS <XR_PAGE_TITLE>
J 0
(-7990 5350);
DISPLAY 0.638298 (-7990 5350);
PAINT PINK (-7990 5350);
DISPLAY INVISIBLE (-7990 5350);
FORCEPROP 1 LAST CUSTOM_TXT_CDS <NAME_2>
J 0
(-3275 150);
FORCEPROP 1 LAST CUSTOM_TXT_CDS <NAME_1>
J 0
(-3275 275);
FORCEPROP 1 LAST CUSTOM_TXT_CDS <Q_NUMBER>
J 0
(-1503 203);
DISPLAY 1.212766 (-1503 203);
FORCEPROP 1 LAST CUSTOM_TXT_CDS <Q_PROJ>
J 0
(-2482 202);
DISPLAY 1.212766 (-2482 202);
FORCEPROP 1 LAST CUSTOM_TXT_CDS <Q_REV>
J 0
(-284 203);
DISPLAY 1.212766 (-284 203);
FORCEPROP 1 LAST CUSTOM_TXT_CDS <CON_PAGE_NUM> OF <CON_TOTAL_PAGES>
J 0
(-546 118);
DISPLAY 0.978723 (-546 118);
FORCEPROP 1 LAST Q_TITLE CPU1 DDR CHF
J 0
(-9400 175);
DISPLAY 2.446809 (-9400 175);
PAINT GREEN (-9400 175);
FORCEPROP 1 LAST Q_DEPT BU9
J 1
(-3863 149);
DISPLAY 1.957447 (-3863 149);
PAINT GREEN (-3863 149);
FORCEPROP 2 LAST PAGE_BORDER TRUE
J 0
(-7990 5350);
DISPLAY 0.638298 (-7990 5350);
PAINT PINK (-7990 5350);
DISPLAY INVISIBLE (-7990 5350);
FORCEPROP 2 LAST CDS_LIB pure_quanta
J 0
(-100 100);
DISPLAY INVISIBLE (-100 100);
FORCEPROP 1 LAST CDS_LMAN_SYM_OUTLINE -9475,6775,100,-125
J 0
(-100 100);
DISPLAY 0.468085 (-100 100);
PAINT GREEN (-100 100);
DISPLAY INVISIBLE (-100 100);
FORCEPROP 1 LAST COMMENT_BODY TRUE
J 0
(-88 87);
DISPLAY 0.978723 (-88 87);
PAINT GREEN (-88 87);
DISPLAY INVISIBLE (-88 87);
FORCEPROP 2 LAST CDS_XR_PAGE_TITLE CR-42 : @T6G_MB_LIB.T6G(SCH_1):PAGE42
J 0
(-7990 5350);
DISPLAY 0.638298 (-7990 5350);
PAINT PINK (-7990 5350);
DISPLAY INVISIBLE (-7990 5350);
WIRE 17 -1 (-3275 6175)(-2650 6175);
FORCEPROP 2 LAST SIG_NAME M_F_CPU1_SA_DQ<31:0>
J 2
(-2710 6185);
DISPLAY 0.489362 (-2710 6185);
WIRE 17 -1 (-3275 5725)(-3275 5675);
WIRE 17 -1 (-3275 5825)(-3275 5725);
WIRE 17 -1 (-3275 5675)(-3275 5625);
WIRE 17 -1 (-3275 5625)(-3275 5575);
WIRE 17 -1 (-3275 5875)(-3275 5825);
WIRE 17 -1 (-3275 5925)(-3275 5875);
WIRE 17 -1 (-3275 5575)(-3275 5525);
WIRE 17 -1 (-3275 5525)(-3275 5475);
WIRE 17 -1 (-3275 5975)(-3275 5925);
WIRE 17 -1 (-3275 6025)(-3275 5975);
WIRE 17 -1 (-3275 5475)(-3275 5425);
WIRE 17 -1 (-3275 5425)(-3275 5375);
WIRE 17 -1 (-3275 6075)(-3275 6025);
WIRE 17 -1 (-3275 6125)(-3275 6075);
WIRE 17 -1 (-3275 5275)(-3275 5375);
WIRE 17 -1 (-3275 5225)(-3275 5275);
WIRE 17 -1 (-3275 6175)(-3275 6125);
WIRE 17 -1 (-3275 5175)(-3275 5225);
WIRE 17 -1 (-3275 5125)(-3275 5175);
WIRE 17 -1 (-3275 5125)(-3275 5075);
WIRE 17 -1 (-3275 5075)(-3275 5025);
WIRE 17 -1 (-3275 5025)(-3275 4975);
WIRE 17 -1 (-3275 4975)(-3275 4925);
WIRE 17 -1 (-3275 4925)(-3275 4825);
WIRE 17 -1 (-3275 4825)(-3275 4775);
WIRE 17 -1 (-3275 4775)(-3275 4725);
WIRE 17 -1 (-3275 4725)(-3275 4675);
WIRE 17 -1 (-3275 4625)(-3275 4675);
WIRE 17 -1 (-3275 4575)(-3275 4625);
WIRE 17 -1 (-3275 4525)(-3275 4575);
WIRE 17 -1 (-3275 4475)(-3275 4525);
WIRE 17 -1 (-3275 4375)(-3275 4325);
WIRE 17 -1 (-3275 4375)(-2650 4375);
FORCEPROP 2 LAST SIG_NAME M_F_CPU1_SB_DQ<31:0>
J 2
(-2710 4385);
DISPLAY 0.489362 (-2710 4385);
WIRE 17 -1 (-3275 4325)(-3275 4275);
WIRE 17 -1 (-3275 4275)(-3275 4225);
WIRE 17 -1 (-3275 4225)(-3275 4175);
WIRE 17 -1 (-3275 4175)(-3275 4125);
WIRE 17 -1 (-3275 4125)(-3275 4075);
WIRE 17 -1 (-3275 4075)(-3275 4025);
WIRE 17 -1 (-3275 4025)(-3275 3925);
WIRE 17 -1 (-3275 3925)(-3275 3875);
WIRE 17 -1 (-3275 3875)(-3275 3825);
WIRE 17 -1 (-3275 3825)(-3275 3775);
WIRE 17 -1 (-3275 3775)(-3275 3725);
WIRE 17 -1 (-3275 3325)(-3275 3275);
WIRE 17 -1 (-3275 3325)(-3275 3375);
WIRE 17 -1 (-3275 3275)(-3275 3225);
WIRE 17 -1 (-3275 3225)(-3275 3175);
WIRE 17 -1 (-3275 3375)(-3275 3425);
WIRE 17 -1 (-3275 3425)(-3275 3475);
WIRE 17 -1 (-3275 3175)(-3275 3125);
WIRE 17 -1 (-3275 3125)(-3275 3025);
WIRE 17 -1 (-3275 3475)(-3275 3575);
WIRE 17 -1 (-3275 3625)(-3275 3575);
WIRE 17 -1 (-3275 3025)(-3275 2975);
WIRE 17 -1 (-3275 2975)(-3275 2925);
WIRE 17 -1 (-3275 3675)(-3275 3625);
WIRE 17 -1 (-3275 3725)(-3275 3675);
WIRE 17 -1 (-3275 2925)(-3275 2875);
WIRE 17 -1 (-3275 2825)(-3275 2875);
WIRE 17 -1 (-3275 2775)(-3275 2825);
WIRE 17 -1 (-3275 2725)(-3275 2775);
WIRE 17 -1 (-3275 2675)(-3275 2725);
WIRE 17 -1 (-3275 2575)(-3275 2525);
WIRE 17 -1 (-3275 2575)(-3275 2600);
WIRE 17 -1 (-3275 2475)(-3275 2525);
WIRE 17 -1 (-3275 2475)(-3275 2425);
WIRE 17 -1 (-3275 2600)(-2775 2600);
FORCEPROP 2 LAST SIG_NAME M_F_CPU1_SA_CB<7:0>
J 2
(-2775 2610);
DISPLAY 0.489362 (-2775 2610);
WIRE 17 -1 (-3275 2375)(-3275 2425);
WIRE 17 -1 (-3275 2325)(-3275 2375);
WIRE 17 -1 (-3275 2275)(-3275 2325);
WIRE 17 -1 (-3275 2225)(-3275 2275);
WIRE 17 -1 (-3275 2125)(-3275 2075);
WIRE 17 -1 (-3275 2125)(-3275 2150);
WIRE 17 -1 (-3275 2025)(-3275 2075);
WIRE 17 -1 (-3275 2025)(-3275 1975);
WIRE 17 -1 (-3275 2150)(-2775 2150);
FORCEPROP 2 LAST SIG_NAME M_F_CPU1_SB_CB<7:0>
J 2
(-2775 2160);
DISPLAY 0.489362 (-2775 2160);
WIRE 17 -1 (-3275 1925)(-3275 1975);
WIRE 17 -1 (-3275 1875)(-3275 1925);
WIRE 17 -1 (-3275 1825)(-3275 1875);
WIRE 17 -1 (-3275 1775)(-3275 1825);
WIRE 17 -1 (-5800 6175)(-5800 6075);
WIRE 17 -1 (-5800 6175)(-6600 6175);
FORCEPROP 2 LAST SIG_NAME M_F_CPU1_SA_DQS_DP<9:0>
J 2
(-6035 6185);
DISPLAY 0.489362 (-6035 6185);
WIRE 17 -1 (-5800 5475)(-5800 5375);
WIRE 17 -1 (-5800 5475)(-5800 5575);
WIRE 17 -1 (-5800 5375)(-5800 5275);
WIRE 17 -1 (-5800 5575)(-5800 5675);
WIRE 17 -1 (-5800 5675)(-5800 5775);
WIRE 17 -1 (-5800 5875)(-5800 5775);
WIRE 17 -1 (-5800 5975)(-5800 5875);
WIRE 17 -1 (-5800 6075)(-5800 5975);
WIRE 17 -1 (-6000 6125)(-6000 6025);
FORCEPROP 2 LAST SIG_NAME M_F_CPU1_SA_DQS_DN<9:0>
J 2
(-6035 6135);
DISPLAY 0.489362 (-6035 6135);
WIRE 17 -1 (-6000 5925)(-6000 5825);
WIRE 17 -1 (-6000 6025)(-6000 5925);
WIRE 17 -1 (-6000 5825)(-6000 5725);
WIRE 17 -1 (-6000 5625)(-6000 5725);
WIRE 17 -1 (-6000 5525)(-6000 5625);
WIRE 17 -1 (-6000 5425)(-6000 5525);
WIRE 17 -1 (-6000 5425)(-6000 5325);
WIRE 17 -1 (-6000 5325)(-6000 5225);
WIRE 17 -1 (-6000 4475)(-6000 4575);
WIRE 17 -1 (-6000 4375)(-6000 4475);
WIRE 17 -1 (-6000 4575)(-6000 4675);
WIRE 17 -1 (-6000 4775)(-6000 4675);
WIRE 17 -1 (-6000 4375)(-6000 4275);
WIRE 17 -1 (-6000 4275)(-6000 4175);
WIRE 17 -1 (-6000 4875)(-6000 4775);
WIRE 17 -1 (-6000 4975)(-6000 4875);
WIRE 17 -1 (-6000 5075)(-6000 4975);
FORCEPROP 2 LAST SIG_NAME M_F_CPU1_SB_DQS_DN<9:0>
J 2
(-6035 5085);
DISPLAY 0.489362 (-6035 5085);
WIRE 17 -1 (-5800 4925)(-5800 4825);
WIRE 17 -1 (-5800 5025)(-5800 4925);
WIRE 17 -1 (-5800 4825)(-5800 4725);
WIRE 17 -1 (-5800 4625)(-5800 4725);
WIRE 17 -1 (-5800 5125)(-5800 5025);
WIRE 17 -1 (-5800 5125)(-6600 5125);
FORCEPROP 2 LAST SIG_NAME M_F_CPU1_SB_DQS_DP<9:0>
J 2
(-6035 5135);
DISPLAY 0.489362 (-6035 5135);
WIRE 17 -1 (-5800 4525)(-5800 4625);
WIRE 17 -1 (-5800 4425)(-5800 4525);
WIRE 17 -1 (-5800 4425)(-5800 4325);
WIRE 17 -1 (-5800 4325)(-5800 4225);
WIRE 17 -1 (-6000 3975)(-6000 4025);
WIRE 17 -1 (-6000 3925)(-6000 3975);
WIRE 17 -1 (-6000 4025)(-6500 4025);
FORCEPROP 2 LAST SIG_NAME M_F_CPU1_SA_CA<6:0>
J 0
(-6500 4035);
DISPLAY 0.489362 (-6500 4035);
WIRE 17 -1 (-6000 3575)(-6000 3625);
WIRE 17 -1 (-6000 3525)(-6000 3575);
WIRE 17 -1 (-6000 3625)(-6500 3625);
FORCEPROP 2 LAST SIG_NAME M_F_CPU1_SB_CA<6:0>
J 0
(-6500 3635);
DISPLAY 0.489362 (-6500 3635);
WIRE 17 -1 (-6000 3875)(-6000 3925);
WIRE 17 -1 (-6000 3475)(-6000 3525);
WIRE 17 -1 (-6000 3825)(-6000 3875);
WIRE 17 -1 (-6000 3775)(-6000 3825);
WIRE 17 -1 (-6000 3725)(-6000 3775);
WIRE 17 -1 (-6000 3425)(-6000 3475);
WIRE 17 -1 (-6000 3375)(-6000 3425);
WIRE 17 -1 (-6000 3325)(-6000 3375);
WIRE 17 -1 (-6000 6125)(-6600 6125);
WIRE 17 -1 (-6000 5075)(-6600 5075);
WIRE 16 -1 (-7450 2300)(-6725 2300);
FORCEPROP 2 LAST SIG_NAME M_F_CPU1_ALERT_N
J 0
(-7410 2310);
DISPLAY 0.489362 (-7410 2310);
WIRE 16 -1 (-6500 1350)(-5400 1350);
FORCEPROP 2 LAST SIG_NAME TP_M_F_CPU1_SA_TEST39F
J 0
(-6485 1360);
DISPLAY 0.489362 (-6485 1360);
FORCEPROP 2 LASTPROP $XRERR UNIQUE?
J 0
(-6740 1350);
DISPLAY 0.638298 (-6740 1350);
PAINT MONO (-6740 1350);
DISPLAY INVISIBLE (-6740 1350);
WIRE 16 -1 (-6525 2300)(-5400 2300);
FORCEPROP 2 LAST SIG_NAME M_F_CPU1_ALERT_R_N
J 0
(-6235 2310);
DISPLAY 0.489362 (-6235 2310);
FORCEPROP 2 LASTPROP $XRERR UNIQUE?
J 0
(-6475 2310);
DISPLAY 0.638298 (-6475 2310);
PAINT MONO (-6475 2310);
DISPLAY INVISIBLE (-6475 2310);
WIRE 16 -1 (-6500 3150)(-5400 3150);
FORCEPROP 2 LAST SIG_NAME M_F_CPU1_CLK_DP<0>
J 0
(-6500 3160);
DISPLAY 0.489362 (-6500 3160);
WIRE 16 -1 (-6500 3100)(-5400 3100);
FORCEPROP 2 LAST SIG_NAME M_F_CPU1_CLK_DN<0>
J 0
(-6500 3110);
DISPLAY 0.489362 (-6500 3110);
WIRE 16 -1 (-6500 3000)(-5400 3000);
FORCEPROP 2 LAST SIG_NAME M_F_CPU1_SA_CS_N<0>
J 0
(-6500 3010);
DISPLAY 0.489362 (-6500 3010);
WIRE 16 -1 (-6500 2950)(-5400 2950);
FORCEPROP 2 LAST SIG_NAME M_F_CPU1_SA_CS_N<1>
J 0
(-6500 2960);
DISPLAY 0.489362 (-6500 2960);
WIRE 16 -1 (-6500 2850)(-5400 2850);
FORCEPROP 2 LAST SIG_NAME M_F_CPU1_SA_RSP<0>
J 0
(-6500 2860);
DISPLAY 0.489362 (-6500 2860);
WIRE 16 -1 (-6500 2750)(-5400 2750);
FORCEPROP 2 LAST SIG_NAME M_F_CPU1_SA_PAR
J 0
(-6500 2760);
DISPLAY 0.489362 (-6500 2760);
WIRE 16 -1 (-6500 2650)(-5400 2650);
FORCEPROP 2 LAST SIG_NAME M_F_CPU1_SB_CS_N<0>
J 0
(-6500 2660);
DISPLAY 0.489362 (-6500 2660);
WIRE 16 -1 (-6500 2600)(-5400 2600);
FORCEPROP 2 LAST SIG_NAME M_F_CPU1_SB_CS_N<1>
J 0
(-6500 2610);
DISPLAY 0.489362 (-6500 2610);
WIRE 16 -1 (-6500 2500)(-5400 2500);
FORCEPROP 2 LAST SIG_NAME M_F_CPU1_SB_RSP<0>
J 0
(-6500 2510);
DISPLAY 0.489362 (-6500 2510);
WIRE 16 -1 (-6500 2400)(-5400 2400);
FORCEPROP 2 LAST SIG_NAME M_F_CPU1_SB_PAR
J 0
(-6500 2410);
DISPLAY 0.489362 (-6500 2410);
WIRE 16 -1 (-6500 2200)(-5400 2200);
FORCEPROP 2 LAST SIG_NAME M_F_CPU1_RESET_N
J 0
(-6500 2210);
DISPLAY 0.489362 (-6500 2210);
WIRE 16 -1 (-5900 3300)(-5400 3300);
WIRE 16 -1 (-5900 3700)(-5400 3700);
WIRE 16 -1 (-5900 3350)(-5400 3350);
WIRE 16 -1 (-5900 3750)(-5400 3750);
WIRE 16 -1 (-5900 3400)(-5400 3400);
WIRE 16 -1 (-5900 3800)(-5400 3800);
WIRE 16 -1 (-5900 3450)(-5400 3450);
WIRE 16 -1 (-5900 3850)(-5400 3850);
WIRE 16 -1 (-5900 3500)(-5400 3500);
WIRE 16 -1 (-5900 3900)(-5400 3900);
WIRE 16 -1 (-5900 3550)(-5400 3550);
WIRE 16 -1 (-5900 3950)(-5400 3950);
WIRE 16 -1 (-5900 3600)(-5400 3600);
WIRE 16 -1 (-5900 4000)(-5400 4000);
WIRE 16 -1 (-5700 4200)(-5400 4200);
WIRE 16 -1 (-5700 5000)(-5400 5000);
WIRE 16 -1 (-5900 4550)(-5400 4550);
WIRE 16 -1 (-5700 5100)(-5400 5100);
WIRE 16 -1 (-5900 4650)(-5400 4650);
WIRE 16 -1 (-5900 4750)(-5400 4750);
WIRE 16 -1 (-5900 4850)(-5400 4850);
WIRE 16 -1 (-5900 4950)(-5400 4950);
WIRE 16 -1 (-5900 5050)(-5400 5050);
WIRE 16 -1 (-5700 4300)(-5400 4300);
WIRE 16 -1 (-5700 4400)(-5400 4400);
WIRE 16 -1 (-5700 4500)(-5400 4500);
WIRE 16 -1 (-5700 4600)(-5400 4600);
WIRE 16 -1 (-5900 4150)(-5400 4150);
WIRE 16 -1 (-5700 4700)(-5400 4700);
WIRE 16 -1 (-5900 4250)(-5400 4250);
WIRE 16 -1 (-5700 4800)(-5400 4800);
WIRE 16 -1 (-5900 4350)(-5400 4350);
WIRE 16 -1 (-5700 4900)(-5400 4900);
WIRE 16 -1 (-5900 4450)(-5400 4450);
WIRE 16 -1 (-5700 5450)(-5400 5450);
WIRE 16 -1 (-5700 5550)(-5400 5550);
WIRE 16 -1 (-5700 5650)(-5400 5650);
WIRE 16 -1 (-5900 5200)(-5400 5200);
WIRE 16 -1 (-5700 5750)(-5400 5750);
WIRE 16 -1 (-5900 5300)(-5400 5300);
WIRE 16 -1 (-5700 5850)(-5400 5850);
WIRE 16 -1 (-5900 5400)(-5400 5400);
WIRE 16 -1 (-5700 5950)(-5400 5950);
WIRE 16 -1 (-5900 5500)(-5400 5500);
WIRE 16 -1 (-5700 6050)(-5400 6050);
WIRE 16 -1 (-5900 5600)(-5400 5600);
WIRE 16 -1 (-5900 5700)(-5400 5700);
WIRE 16 -1 (-5900 5800)(-5400 5800);
WIRE 16 -1 (-5900 5900)(-5400 5900);
WIRE 16 -1 (-5900 6000)(-5400 6000);
WIRE 16 -1 (-5900 6100)(-5400 6100);
WIRE 16 -1 (-5700 5250)(-5400 5250);
WIRE 16 -1 (-5700 5350)(-5400 5350);
WIRE 16 -1 (-5700 6150)(-5400 6150);
WIRE 16 -1 (-3800 1750)(-3375 1750);
WIRE 16 -1 (-3800 1800)(-3375 1800);
WIRE 16 -1 (-3800 1850)(-3375 1850);
WIRE 16 -1 (-3800 1900)(-3375 1900);
WIRE 16 -1 (-3800 1950)(-3375 1950);
WIRE 16 -1 (-3800 2000)(-3375 2000);
WIRE 16 -1 (-3800 2750)(-3375 2750);
WIRE 16 -1 (-3800 2800)(-3375 2800);
WIRE 16 -1 (-3800 2850)(-3375 2850);
WIRE 16 -1 (-3800 2900)(-3375 2900);
WIRE 16 -1 (-3800 2950)(-3375 2950);
WIRE 16 -1 (-3800 3000)(-3375 3000);
WIRE 16 -1 (-3800 2200)(-3375 2200);
WIRE 16 -1 (-3800 2050)(-3375 2050);
WIRE 16 -1 (-3800 2250)(-3375 2250);
WIRE 16 -1 (-3800 2100)(-3375 2100);
WIRE 16 -1 (-3800 2650)(-3375 2650);
WIRE 16 -1 (-3800 2300)(-3375 2300);
WIRE 16 -1 (-3800 2700)(-3375 2700);
WIRE 16 -1 (-3800 2350)(-3375 2350);
WIRE 16 -1 (-3800 2400)(-3375 2400);
WIRE 16 -1 (-3800 2450)(-3375 2450);
WIRE 16 -1 (-3800 2500)(-3375 2500);
WIRE 16 -1 (-3800 2550)(-3375 2550);
WIRE 16 -1 (-3800 4050)(-3375 4050);
WIRE 16 -1 (-3800 3350)(-3375 3350);
WIRE 16 -1 (-3800 3400)(-3375 3400);
WIRE 16 -1 (-3800 3450)(-3375 3450);
WIRE 16 -1 (-3800 3550)(-3375 3550);
WIRE 16 -1 (-3800 3600)(-3375 3600);
WIRE 16 -1 (-3800 3650)(-3375 3650);
WIRE 16 -1 (-3800 3700)(-3375 3700);
WIRE 16 -1 (-3800 3100)(-3375 3100);
WIRE 16 -1 (-3800 3750)(-3375 3750);
WIRE 16 -1 (-3800 3150)(-3375 3150);
WIRE 16 -1 (-3800 3800)(-3375 3800);
WIRE 16 -1 (-3800 3200)(-3375 3200);
WIRE 16 -1 (-3800 3250)(-3375 3250);
WIRE 16 -1 (-3800 3850)(-3375 3850);
WIRE 16 -1 (-3800 3900)(-3375 3900);
WIRE 16 -1 (-3800 4000)(-3375 4000);
WIRE 16 -1 (-3800 3300)(-3375 3300);
WIRE 16 -1 (-3800 4100)(-3375 4100);
WIRE 16 -1 (-3800 4150)(-3375 4150);
WIRE 16 -1 (-3800 4200)(-3375 4200);
WIRE 16 -1 (-3800 4250)(-3375 4250);
WIRE 16 -1 (-3800 5100)(-3375 5100);
WIRE 16 -1 (-3800 4300)(-3375 4300);
WIRE 16 -1 (-3800 4550)(-3375 4550);
WIRE 16 -1 (-3800 4350)(-3375 4350);
WIRE 16 -1 (-3800 4600)(-3375 4600);
WIRE 16 -1 (-3800 4650)(-3375 4650);
WIRE 16 -1 (-3800 4700)(-3375 4700);
WIRE 16 -1 (-3800 4750)(-3375 4750);
WIRE 16 -1 (-3800 4800)(-3375 4800);
WIRE 16 -1 (-3800 4900)(-3375 4900);
WIRE 16 -1 (-3800 4950)(-3375 4950);
WIRE 16 -1 (-3800 5000)(-3375 5000);
WIRE 16 -1 (-3800 5050)(-3375 5050);
WIRE 16 -1 (-3800 4450)(-3375 4450);
WIRE 16 -1 (-3800 4500)(-3375 4500);
WIRE 16 -1 (-3800 5800)(-3375 5800);
WIRE 16 -1 (-3800 5850)(-3375 5850);
WIRE 16 -1 (-3800 5900)(-3375 5900);
WIRE 16 -1 (-3800 5950)(-3375 5950);
WIRE 16 -1 (-3800 6000)(-3375 6000);
WIRE 16 -1 (-3800 6050)(-3375 6050);
WIRE 16 -1 (-3800 6100)(-3375 6100);
WIRE 16 -1 (-3800 5150)(-3375 5150);
WIRE 16 -1 (-3800 5200)(-3375 5200);
WIRE 16 -1 (-3800 5250)(-3375 5250);
WIRE 16 -1 (-3800 5350)(-3375 5350);
WIRE 16 -1 (-3800 5400)(-3375 5400);
WIRE 16 -1 (-3800 5450)(-3375 5450);
WIRE 16 -1 (-3800 5500)(-3375 5500);
WIRE 16 -1 (-3800 5550)(-3375 5550);
WIRE 16 -1 (-3800 5600)(-3375 5600);
WIRE 16 -1 (-3800 5650)(-3375 5650);
WIRE 16 -1 (-3800 5700)(-3375 5700);
WIRE 16 -1 (-3800 6150)(-3375 6150);
QUIT
